FILE_TYPE = MACRO_DRAWING;
SET COLOR_WIRE YELLOW;
SET COLOR_PROP ORANGE;
SET COLOR_DOT WHITE;
SET COLOR_ARC YELLOW;
SET COLOR_BODY GREEN;
SET COLOR_NOTE PURPLE;
SET PROP_DISPLAY VALUE;
SET PAGE_NUMBER P379;
FORCEADD UNIVERSAL_POWER..1
(-8875 5925);
FORCEPROP 3 LASTPIN (-8875 5875) SIG_NAME P3V3_AUX\g
J 0
(-8865 5885);
DISPLAY 0.659574 (-8865 5885);
PAINT MONO (-8865 5885);
DISPLAY INVISIBLE (-8865 5885);
FORCEPROP 1 LAST HDL_POWER P3V3_AUX
J 1
(-8875 5975);
DISPLAY 0.872340 (-8875 5975);
PAINT YELLOW (-8875 5975);
FORCEPROP 2 LAST CDS_LIB pure_quanta_power
J 0
(-8875 5925);
DISPLAY INVISIBLE (-8875 5925);
FORCEPROP 1 LAST PATH I1
J 0
(-8825 5950);
DISPLAY 0.872340 (-8825 5950);
PAINT AQUA (-8825 5950);
DISPLAY INVISIBLE (-8825 5950);
FORCEADD OFFPAGE..1
(-6200 3500);
FORCEPROP 2 LAST $XR0 183 
J 0
(-6452 3500);
DISPLAY 0.638298 (-6452 3500);
PAINT MONO (-6452 3500);
FORCEPROP 2 LAST CDS_LIB standard
J 2
(-6200 3500);
DISPLAY INVISIBLE (-6200 3500);
FORCEPROP 1 LAST OFFPAGE TRUE
J 0
(-5875 3375);
DISPLAY 1.170213 (-5875 3375);
PAINT GREEN (-5875 3375);
DISPLAY INVISIBLE (-5875 3375);
FORCEPROP 1 LAST COMMENT_BODY TRUE
J 0
(-6075 3400);
DISPLAY 1.170213 (-6075 3400);
PAINT GREEN (-6075 3400);
DISPLAY INVISIBLE (-6075 3400);
FORCEPROP 2 LAST PATH I10
J 0
(-6450 3550);
DISPLAY 0.680851 (-6450 3550);
DISPLAY INVISIBLE (-6450 3550);
FORCEADD OFFPAGE..1
(-6425 3400);
FORCEPROP 2 LAST $XR0 151 
J 0
(-6677 3400);
DISPLAY 0.638298 (-6677 3400);
PAINT MONO (-6677 3400);
FORCEPROP 2 LAST CDS_LIB standard
J 0
(-6425 3400);
DISPLAY INVISIBLE (-6425 3400);
FORCEPROP 1 LAST OFFPAGE TRUE
J 0
(-6100 3275);
DISPLAY 1.170213 (-6100 3275);
PAINT GREEN (-6100 3275);
DISPLAY INVISIBLE (-6100 3275);
FORCEPROP 1 LAST COMMENT_BODY TRUE
J 0
(-6300 3300);
DISPLAY 1.170213 (-6300 3300);
PAINT GREEN (-6300 3300);
DISPLAY INVISIBLE (-6300 3300);
FORCEPROP 2 LAST PATH I11
J 0
(-6675 3450);
DISPLAY 0.680851 (-6675 3450);
DISPLAY INVISIBLE (-6675 3450);
FORCEADD OFFPAGE..1
(-6200 3600);
FORCEPROP 2 LAST $XR0 55 
J 0
(-6421 3600);
DISPLAY 0.638298 (-6421 3600);
PAINT MONO (-6421 3600);
FORCEPROP 2 LAST CDS_LIB standard
J 0
(-6200 3600);
DISPLAY INVISIBLE (-6200 3600);
FORCEPROP 1 LAST OFFPAGE TRUE
J 0
(-5875 3475);
DISPLAY 1.170213 (-5875 3475);
PAINT GREEN (-5875 3475);
DISPLAY INVISIBLE (-5875 3475);
FORCEPROP 1 LAST COMMENT_BODY TRUE
J 0
(-6075 3500);
DISPLAY 1.170213 (-6075 3500);
PAINT GREEN (-6075 3500);
DISPLAY INVISIBLE (-6075 3500);
FORCEPROP 2 LAST PATH I12
J 0
(-6450 3650);
DISPLAY 0.680851 (-6450 3650);
DISPLAY INVISIBLE (-6450 3650);
FORCEADD OFFPAGE..1
(-6200 3650);
FORCEPROP 2 LAST $XR0 55 
J 0
(-6421 3650);
DISPLAY 0.638298 (-6421 3650);
PAINT MONO (-6421 3650);
FORCEPROP 2 LAST CDS_LIB standard
J 0
(-6200 3650);
DISPLAY INVISIBLE (-6200 3650);
FORCEPROP 1 LAST OFFPAGE TRUE
J 0
(-5875 3525);
DISPLAY 1.170213 (-5875 3525);
PAINT GREEN (-5875 3525);
DISPLAY INVISIBLE (-5875 3525);
FORCEPROP 1 LAST COMMENT_BODY TRUE
J 0
(-6075 3550);
DISPLAY 1.170213 (-6075 3550);
PAINT GREEN (-6075 3550);
DISPLAY INVISIBLE (-6075 3550);
FORCEPROP 2 LAST PATH I13
J 0
(-6450 3700);
DISPLAY 0.680851 (-6450 3700);
DISPLAY INVISIBLE (-6450 3700);
FORCEADD OFFPAGE..2
(-5200 1350);
FORCEPROP 2 LAST $XR0 183 
J 0
(-5011 1350);
DISPLAY 0.638298 (-5011 1350);
PAINT MONO (-5011 1350);
FORCEPROP 2 LAST CDS_LIB standard
J 0
(-5200 1350);
DISPLAY INVISIBLE (-5200 1350);
FORCEPROP 1 LAST OFFPAGE TRUE
J 0
(-4875 1225);
DISPLAY 0.872340 (-4875 1225);
DISPLAY INVISIBLE (-4875 1225);
FORCEPROP 1 LAST COMMENT_BODY TRUE
J 0
(-5245 1255);
DISPLAY 0.872340 (-5245 1255);
PAINT GREEN (-5245 1255);
DISPLAY INVISIBLE (-5245 1255);
FORCEPROP 2 LAST PATH I14
J 0
(-5000 1400);
DISPLAY 0.680851 (-5000 1400);
DISPLAY INVISIBLE (-5000 1400);
FORCEADD Q_RES..2
(-3925 1100);
FORCEPROP 1 LAST LOCATION R585
J 0
(-3880 1225);
DISPLAY 0.978723 (-3880 1225);
FORCEPROP 0 LAST $SEC 1
J 0
(-3875 1275);
DISPLAY 0.680851 (-3875 1275);
PAINT MONO (-3875 1275);
DISPLAY INVISIBLE (-3875 1275);
FORCEPROP 0 LAST CDS_SEC 1
J 0
(-3875 1275);
DISPLAY 1.021277 (-3875 1275);
DISPLAY INVISIBLE (-3875 1275);
FORCEPROP 1 LASTPIN (-3925 1200) $PN 1
J 0
(-3920 1162);
DISPLAY 0.787234 (-3920 1162);
PAINT MONO (-3920 1162);
FORCEPROP 1 LASTPIN (-3925 1000) $PN 2
J 0
(-3920 1010);
DISPLAY 0.787234 (-3920 1010);
PAINT MONO (-3920 1010);
FORCEPROP 1 LAST TOLERANCE 1%
J 0
(-3880 1125);
DISPLAY 0.638298 (-3880 1125);
FORCEPROP 1 LAST VALUE 10K
J 0
(-3880 1175);
DISPLAY 0.638298 (-3880 1175);
FORCEPROP 1 LAST PACK_TYPE 0402LF
J 0
(-3885 975);
DISPLAY 0.638298 (-3885 975);
FORCEPROP 1 LAST WATTAGE 1/16W
J 0
(-3885 1075);
DISPLAY 0.638298 (-3885 1075);
FORCEPROP 1 LAST MATERIAL CHIP
J 0
(-3900 1025);
DISPLAY 0.638298 (-3900 1025);
FORCEPROP 2 LAST CDS_LIB pure_quanta
J 0
(-3925 1100);
DISPLAY INVISIBLE (-3925 1100);
FORCEPROP 1 LAST PATH I15
J 0
(-3875 1275);
DISPLAY 0.978723 (-3875 1275);
PAINT WHITE (-3875 1275);
DISPLAY INVISIBLE (-3875 1275);
FORCEPROP 1 LAST PART_NUMBER CS31002FB08
J 0
(-3885 975);
DISPLAY 0.638298 (-3885 975);
DISPLAY INVISIBLE (-3885 975);
FORCEADD UNIVERSAL_GND..1
(-3925 850);
FORCEPROP 3 LASTPIN (-3925 900) SIG_NAME GND\g
J 0
(-3915 910);
DISPLAY 0.659574 (-3915 910);
PAINT MONO (-3915 910);
DISPLAY INVISIBLE (-3915 910);
FORCEPROP 2 LAST CDS_LIB pure_quanta_power
J 0
(-3925 850);
DISPLAY INVISIBLE (-3925 850);
FORCEPROP 1 LAST HDL_POWER GND
J 1
(-3900 775);
DISPLAY 0.872340 (-3900 775);
PAINT GREEN (-3900 775);
DISPLAY INVISIBLE (-3900 775);
FORCEPROP 1 LAST PATH I16
J 0
(-3850 850);
DISPLAY 0.872340 (-3850 850);
PAINT AQUA (-3850 850);
DISPLAY INVISIBLE (-3850 850);
FORCEADD Q_RES..2
(-3925 1575);
FORCEPROP 1 LAST LOCATION R580
J 0
(-3880 1700);
DISPLAY 0.978723 (-3880 1700);
FORCEPROP 0 LAST $SEC 1
J 0
(-3875 1750);
DISPLAY 0.680851 (-3875 1750);
PAINT MONO (-3875 1750);
DISPLAY INVISIBLE (-3875 1750);
FORCEPROP 0 LAST CDS_SEC 1
J 0
(-3875 1750);
DISPLAY 1.021277 (-3875 1750);
DISPLAY INVISIBLE (-3875 1750);
FORCEPROP 1 LASTPIN (-3925 1675) $PN 1
J 0
(-3920 1637);
DISPLAY 0.787234 (-3920 1637);
PAINT MONO (-3920 1637);
FORCEPROP 1 LASTPIN (-3925 1475) $PN 2
J 0
(-3920 1485);
DISPLAY 0.787234 (-3920 1485);
PAINT MONO (-3920 1485);
FORCEPROP 1 LAST WATTAGE 1/16W
J 0
(-3885 1550);
DISPLAY 0.638298 (-3885 1550);
FORCEPROP 1 LAST TOLERANCE 1%
J 0
(-3880 1600);
DISPLAY 0.638298 (-3880 1600);
FORCEPROP 1 LAST MATERIAL CHIP
J 0
(-3900 1500);
DISPLAY 0.638298 (-3900 1500);
FORCEPROP 1 LAST PACK_TYPE 0402LF
J 0
(-3885 1450);
DISPLAY 0.638298 (-3885 1450);
FORCEPROP 1 LAST VALUE 10K
J 0
(-3880 1650);
DISPLAY 0.638298 (-3880 1650);
FORCEPROP 2 LAST CDS_LIB pure_quanta
J 0
(-3925 1575);
DISPLAY INVISIBLE (-3925 1575);
FORCEPROP 1 LAST PATH I17
J 0
(-3875 1750);
DISPLAY 0.978723 (-3875 1750);
PAINT WHITE (-3875 1750);
DISPLAY INVISIBLE (-3875 1750);
FORCEPROP 1 LAST PART_NUMBER CS31002FB08
J 0
(-3885 1450);
DISPLAY 0.638298 (-3885 1450);
DISPLAY INVISIBLE (-3885 1450);
FORCEADD UNIVERSAL_POWER..1
(-3925 1875);
FORCEPROP 3 LASTPIN (-3925 1825) SIG_NAME P3V3_AUX\g
J 0
(-3915 1835);
DISPLAY 0.659574 (-3915 1835);
PAINT MONO (-3915 1835);
DISPLAY INVISIBLE (-3915 1835);
FORCEPROP 1 LAST HDL_POWER P3V3_AUX
J 1
(-3925 1925);
DISPLAY 0.872340 (-3925 1925);
PAINT YELLOW (-3925 1925);
FORCEPROP 2 LAST CDS_LIB pure_quanta_power
J 0
(-3925 1875);
DISPLAY INVISIBLE (-3925 1875);
FORCEPROP 1 LAST PATH I18
J 0
(-3875 1900);
DISPLAY 0.872340 (-3875 1900);
PAINT AQUA (-3875 1900);
DISPLAY INVISIBLE (-3875 1900);
FORCEADD Q_INDUCTOR..1
(-8450 5850);
FORCEPROP 1 LAST LOCATION L1
J 0
(-8575 6010);
DISPLAY 0.723404 (-8575 6010);
PAINT GREEN (-8575 6010);
FORCEPROP 0 LAST $SEC 1
J 0
(-8575 6150);
DISPLAY 0.680851 (-8575 6150);
PAINT MONO (-8575 6150);
DISPLAY INVISIBLE (-8575 6150);
FORCEPROP 0 LAST CDS_SEC 1
J 0
(-8575 6150);
DISPLAY 1.021277 (-8575 6150);
DISPLAY INVISIBLE (-8575 6150);
FORCEPROP 0 LASTPIN (-8550 5825) $PN 1
J 2
(-8560 5835);
DISPLAY 0.680851 (-8560 5835);
PAINT MONO (-8560 5835);
FORCEPROP 0 LASTPIN (-8350 5825) $PN 2
J 0
(-8340 5835);
DISPLAY 0.680851 (-8340 5835);
PAINT MONO (-8340 5835);
FORCEPROP 1 LAST MATERIAL IND
J 0
(-8575 5905);
DISPLAY 0.723404 (-8575 5905);
PAINT GREEN (-8575 5905);
FORCEPROP 2 LAST PACK_TYPE SMLF
J 0
(-8575 6100);
DISPLAY 0.638298 (-8575 6100);
FORCEPROP 2 LAST VALUE FCM2012KF-601T/0.5A
J 0
(-8575 6050);
DISPLAY 0.638298 (-8575 6050);
FORCEPROP 2 LAST CDS_LIB pure_quanta
J 0
(-8450 5850);
DISPLAY INVISIBLE (-8450 5850);
FORCEPROP 1 LAST NEEDS_NO_SIZE TRUE
J 0
(-8450 5850);
DISPLAY 0.468085 (-8450 5850);
PAINT GREEN (-8450 5850);
DISPLAY INVISIBLE (-8450 5850);
FORCEPROP 1 LAST PATH I2
J 0
(-8375 5905);
DISPLAY 0.723404 (-8375 5905);
PAINT GREEN (-8375 5905);
DISPLAY INVISIBLE (-8375 5905);
FORCEPROP 1 LAST PART_NUMBER CX601T05003
J 0
(-8575 5960);
DISPLAY 0.723404 (-8575 5960);
PAINT GREEN (-8575 5960);
DISPLAY INVISIBLE (-8575 5960);
FORCEADD Q_RES..1
(-7550 5000);
FORCEPROP 1 LAST LOCATION R555
J 0
(-7775 5000);
DISPLAY 0.638298 (-7775 5000);
FORCEPROP 0 LAST $SEC 1
J 0
(-7375 5150);
DISPLAY 0.680851 (-7375 5150);
PAINT MONO (-7375 5150);
DISPLAY INVISIBLE (-7375 5150);
FORCEPROP 0 LAST CDS_SEC 1
J 0
(-7375 5150);
DISPLAY 1.021277 (-7375 5150);
DISPLAY INVISIBLE (-7375 5150);
FORCEPROP 1 LASTPIN (-7650 5000) $PN 1
J 0
(-7638 5012);
DISPLAY 0.787234 (-7638 5012);
PAINT MONO (-7638 5012);
FORCEPROP 1 LASTPIN (-7450 5000) $PN 2
J 0
(-7488 5012);
DISPLAY 0.787234 (-7488 5012);
PAINT MONO (-7488 5012);
FORCEPROP 1 LAST WATTAGE 1/10W
J 2
(-7375 5125);
DISPLAY 0.510638 (-7375 5125);
FORCEPROP 1 LAST PACK_TYPE 0603LF
J 0
(-7700 5125);
DISPLAY 0.510638 (-7700 5125);
FORCEPROP 1 LAST VALUE 1
J 2
(-7350 5000);
DISPLAY 0.638298 (-7350 5000);
FORCEPROP 1 LAST MATERIAL CHIP
J 0
(-7225 5000);
DISPLAY 0.638298 (-7225 5000);
FORCEPROP 1 LAST TOLERANCE 1%
J 0
(-7325 5000);
DISPLAY 0.638298 (-7325 5000);
FORCEPROP 2 LAST CDS_LIB pure_quanta
J 0
(-7550 5000);
DISPLAY INVISIBLE (-7550 5000);
FORCEPROP 1 LAST PATH I20
J 0
(-7600 5150);
DISPLAY 0.978723 (-7600 5150);
PAINT WHITE (-7600 5150);
DISPLAY INVISIBLE (-7600 5150);
FORCEPROP 1 LAST PART_NUMBER CS-1003F900
J 0
(-7700 5075);
DISPLAY 0.510638 (-7700 5075);
DISPLAY INVISIBLE (-7700 5075);
FORCEADD Q_RES..1
(-7600 5825);
FORCEPROP 1 LAST LOCATION R586
J 0
(-7800 5825);
DISPLAY 0.638298 (-7800 5825);
FORCEPROP 0 LAST $SEC 1
J 0
(-7425 5975);
DISPLAY 0.680851 (-7425 5975);
PAINT MONO (-7425 5975);
DISPLAY INVISIBLE (-7425 5975);
FORCEPROP 0 LAST CDS_SEC 1
J 0
(-7425 5975);
DISPLAY 1.021277 (-7425 5975);
DISPLAY INVISIBLE (-7425 5975);
FORCEPROP 1 LASTPIN (-7700 5825) $PN 1
J 0
(-7688 5837);
DISPLAY 0.787234 (-7688 5837);
PAINT MONO (-7688 5837);
FORCEPROP 1 LASTPIN (-7500 5825) $PN 2
J 0
(-7538 5837);
DISPLAY 0.787234 (-7538 5837);
PAINT MONO (-7538 5837);
FORCEPROP 1 LAST WATTAGE 1/10W
J 2
(-7425 5950);
DISPLAY 0.510638 (-7425 5950);
FORCEPROP 1 LAST MATERIAL CHIP
J 0
(-7275 5825);
DISPLAY 0.638298 (-7275 5825);
FORCEPROP 1 LAST VALUE 1
J 2
(-7400 5825);
DISPLAY 0.638298 (-7400 5825);
FORCEPROP 1 LAST PACK_TYPE 0603LF
J 0
(-7750 5950);
DISPLAY 0.510638 (-7750 5950);
FORCEPROP 1 LAST TOLERANCE 1%
J 0
(-7375 5825);
DISPLAY 0.638298 (-7375 5825);
FORCEPROP 2 LAST CDS_LIB pure_quanta
J 0
(-7600 5825);
DISPLAY INVISIBLE (-7600 5825);
FORCEPROP 1 LAST PATH I21
J 0
(-7650 5975);
DISPLAY 0.978723 (-7650 5975);
PAINT WHITE (-7650 5975);
DISPLAY INVISIBLE (-7650 5975);
FORCEPROP 1 LAST PART_NUMBER CS-1003F900
J 0
(-7750 5900);
DISPLAY 0.510638 (-7750 5900);
DISPLAY INVISIBLE (-7750 5900);
FORCEADD UNIVERSAL_GND..1
(-6825 5275);
FORCEPROP 3 LASTPIN (-6825 5325) SIG_NAME GND\g
J 0
(-6815 5335);
DISPLAY 0.659574 (-6815 5335);
PAINT MONO (-6815 5335);
DISPLAY INVISIBLE (-6815 5335);
FORCEPROP 2 LAST CDS_LIB pure_quanta_power
J 0
(-6825 5275);
DISPLAY INVISIBLE (-6825 5275);
FORCEPROP 1 LAST HDL_POWER GND
J 1
(-6800 5200);
DISPLAY 0.872340 (-6800 5200);
PAINT GREEN (-6800 5200);
DISPLAY INVISIBLE (-6800 5200);
FORCEPROP 1 LAST PATH I23
J 0
(-6750 5275);
DISPLAY 0.872340 (-6750 5275);
PAINT AQUA (-6750 5275);
DISPLAY INVISIBLE (-6750 5275);
FORCEADD Q_CAP..1
(-6825 5650);
FORCEPROP 1 LAST LOCATION C68
J 0
(-6775 5750);
DISPLAY 0.978723 (-6775 5750);
FORCEPROP 0 LAST $SEC 1
J 0
(-6775 5800);
DISPLAY 0.680851 (-6775 5800);
PAINT MONO (-6775 5800);
DISPLAY INVISIBLE (-6775 5800);
FORCEPROP 0 LAST CDS_SEC 1
J 0
(-6775 5800);
DISPLAY 1.021277 (-6775 5800);
DISPLAY INVISIBLE (-6775 5800);
FORCEPROP 1 LASTPIN (-6825 5750) $PN 1
J 0
(-6815 5730);
DISPLAY 0.787234 (-6815 5730);
PAINT MONO (-6815 5730);
FORCEPROP 1 LASTPIN (-6825 5550) $PN 2
J 0
(-6815 5530);
DISPLAY 0.787234 (-6815 5530);
PAINT MONO (-6815 5530);
FORCEPROP 1 LAST VOLTAGE 25V
J 0
(-6775 5650);
DISPLAY 0.510638 (-6775 5650);
FORCEPROP 1 LAST MATERIAL X7R
J 0
(-6775 5550);
DISPLAY 0.510638 (-6775 5550);
FORCEPROP 1 LAST VALUE 0.1UF
J 0
(-6775 5700);
DISPLAY 0.510638 (-6775 5700);
FORCEPROP 1 LAST TOLERANCE 10%
J 0
(-6775 5600);
DISPLAY 0.510638 (-6775 5600);
FORCEPROP 1 LAST PACK_TYPE 0402
J 0
(-6775 5450);
DISPLAY 0.510638 (-6775 5450);
FORCEPROP 2 LAST CDS_LIB pure_quanta
J 0
(-6825 5650);
DISPLAY INVISIBLE (-6825 5650);
FORCEPROP 1 LAST PATH I24
J 0
(-6775 5800);
DISPLAY 0.978723 (-6775 5800);
PAINT WHITE (-6775 5800);
DISPLAY INVISIBLE (-6775 5800);
FORCEPROP 1 LAST PART_NUMBER CH4104K1B00
J 0
(-6775 5500);
DISPLAY 0.404255 (-6775 5500);
DISPLAY INVISIBLE (-6775 5500);
FORCEADD UNIVERSAL_GND..1
(-6800 4475);
FORCEPROP 3 LASTPIN (-6800 4525) SIG_NAME GND\g
J 0
(-6790 4535);
DISPLAY 0.659574 (-6790 4535);
PAINT MONO (-6790 4535);
DISPLAY INVISIBLE (-6790 4535);
FORCEPROP 2 LAST CDS_LIB pure_quanta_power
J 0
(-6800 4475);
DISPLAY INVISIBLE (-6800 4475);
FORCEPROP 1 LAST HDL_POWER GND
J 1
(-6775 4400);
DISPLAY 0.872340 (-6775 4400);
PAINT GREEN (-6775 4400);
DISPLAY INVISIBLE (-6775 4400);
FORCEPROP 1 LAST PATH I25
J 0
(-6725 4475);
DISPLAY 0.872340 (-6725 4475);
PAINT AQUA (-6725 4475);
DISPLAY INVISIBLE (-6725 4475);
FORCEADD Q_CAP..1
(-6800 4850);
FORCEPROP 1 LAST LOCATION C84
J 0
(-6750 4950);
DISPLAY 0.978723 (-6750 4950);
FORCEPROP 0 LAST $SEC 1
J 0
(-6750 5000);
DISPLAY 0.680851 (-6750 5000);
PAINT MONO (-6750 5000);
DISPLAY INVISIBLE (-6750 5000);
FORCEPROP 0 LAST CDS_SEC 1
J 0
(-6750 5000);
DISPLAY 1.021277 (-6750 5000);
DISPLAY INVISIBLE (-6750 5000);
FORCEPROP 1 LASTPIN (-6800 4950) $PN 1
J 0
(-6790 4930);
DISPLAY 0.787234 (-6790 4930);
PAINT MONO (-6790 4930);
FORCEPROP 1 LASTPIN (-6800 4750) $PN 2
J 0
(-6790 4730);
DISPLAY 0.787234 (-6790 4730);
PAINT MONO (-6790 4730);
FORCEPROP 1 LAST PACK_TYPE 0402
J 0
(-6750 4650);
DISPLAY 0.510638 (-6750 4650);
FORCEPROP 1 LAST TOLERANCE 10%
J 0
(-6750 4800);
DISPLAY 0.510638 (-6750 4800);
FORCEPROP 1 LAST MATERIAL X7R
J 0
(-6750 4750);
DISPLAY 0.510638 (-6750 4750);
FORCEPROP 1 LAST VOLTAGE 25V
J 0
(-6750 4850);
DISPLAY 0.510638 (-6750 4850);
FORCEPROP 1 LAST VALUE 0.1UF
J 0
(-6750 4900);
DISPLAY 0.510638 (-6750 4900);
FORCEPROP 2 LAST CDS_LIB pure_quanta
J 0
(-6800 4850);
DISPLAY INVISIBLE (-6800 4850);
FORCEPROP 1 LAST PATH I26
J 0
(-6750 5000);
DISPLAY 0.978723 (-6750 5000);
PAINT WHITE (-6750 5000);
DISPLAY INVISIBLE (-6750 5000);
FORCEPROP 1 LAST PART_NUMBER CH4104K1B00
J 0
(-6750 4700);
DISPLAY 0.404255 (-6750 4700);
DISPLAY INVISIBLE (-6750 4700);
FORCEADD UNIVERSAL_POWER..1
(-5850 4075);
FORCEPROP 3 LASTPIN (-5850 4025) SIG_NAME P3V3_9ZXL045_P1_VDDR\g
J 0
(-5840 4035);
DISPLAY 0.659574 (-5840 4035);
PAINT MONO (-5840 4035);
DISPLAY INVISIBLE (-5840 4035);
FORCEPROP 1 LAST HDL_POWER P3V3_9ZXL045_P1_VDDR
J 1
(-5900 4125);
DISPLAY 0.872340 (-5900 4125);
PAINT SKYBLUE (-5900 4125);
FORCEPROP 2 LAST CDS_LIB pure_quanta_power
J 0
(-5850 4075);
DISPLAY INVISIBLE (-5850 4075);
FORCEPROP 1 LAST PATH I27
J 0
(-5800 4100);
DISPLAY 0.872340 (-5800 4100);
PAINT AQUA (-5800 4100);
DISPLAY INVISIBLE (-5800 4100);
FORCEADD UNIVERSAL_POWER..1
(-6800 5100);
FORCEPROP 3 LASTPIN (-6800 5050) SIG_NAME P3V3_9ZXL045_P1_VDDR\g
J 0
(-6790 5060);
DISPLAY 0.659574 (-6790 5060);
PAINT MONO (-6790 5060);
DISPLAY INVISIBLE (-6790 5060);
FORCEPROP 1 LAST HDL_POWER P3V3_9ZXL045_P1_VDDR
J 1
(-6800 5150);
DISPLAY 0.872340 (-6800 5150);
PAINT SKYBLUE (-6800 5150);
FORCEPROP 2 LAST CDS_LIB pure_quanta_power
J 0
(-6800 5100);
DISPLAY INVISIBLE (-6800 5100);
FORCEPROP 1 LAST PATH I28
J 0
(-6750 5125);
DISPLAY 0.872340 (-6750 5125);
PAINT AQUA (-6750 5125);
DISPLAY INVISIBLE (-6750 5125);
FORCEADD UNIVERSAL_POWER..1
(-6825 5900);
FORCEPROP 3 LASTPIN (-6825 5850) SIG_NAME P3V3_9ZXL045_P1_VDDA\g
J 0
(-6815 5860);
DISPLAY 0.659574 (-6815 5860);
PAINT MONO (-6815 5860);
DISPLAY INVISIBLE (-6815 5860);
FORCEPROP 1 LAST HDL_POWER P3V3_9ZXL045_P1_VDDA
J 1
(-6825 5950);
DISPLAY 0.872340 (-6825 5950);
PAINT SKYBLUE (-6825 5950);
FORCEPROP 2 LAST CDS_LIB pure_quanta_power
J 0
(-6825 5900);
DISPLAY INVISIBLE (-6825 5900);
FORCEPROP 1 LAST PATH I29
J 0
(-6775 5925);
DISPLAY 0.872340 (-6775 5925);
PAINT AQUA (-6775 5925);
DISPLAY INVISIBLE (-6775 5925);
FORCEADD UNIVERSAL_GND..1
(-5925 900);
FORCEPROP 3 LASTPIN (-5925 950) SIG_NAME GND\g
J 0
(-5915 960);
DISPLAY 0.659574 (-5915 960);
PAINT MONO (-5915 960);
DISPLAY INVISIBLE (-5915 960);
FORCEPROP 2 LAST CDS_LIB pure_quanta_power
J 0
(-5925 900);
DISPLAY INVISIBLE (-5925 900);
FORCEPROP 1 LAST HDL_POWER GND
J 1
(-5900 825);
DISPLAY 0.872340 (-5900 825);
PAINT GREEN (-5900 825);
DISPLAY INVISIBLE (-5900 825);
FORCEPROP 1 LAST PATH I3
J 0
(-5850 900);
DISPLAY 0.872340 (-5850 900);
PAINT AQUA (-5850 900);
DISPLAY INVISIBLE (-5850 900);
FORCEADD UNIVERSAL_POWER..1
(-5450 4375);
FORCEPROP 3 LASTPIN (-5450 4325) SIG_NAME P3V3_9ZXL045_P1_VDD\g
J 0
(-5440 4335);
DISPLAY 0.659574 (-5440 4335);
PAINT MONO (-5440 4335);
DISPLAY INVISIBLE (-5440 4335);
FORCEPROP 1 LAST HDL_POWER P3V3_9ZXL045_P1_VDD
J 1
(-5450 4425);
DISPLAY 0.872340 (-5450 4425);
PAINT SKYBLUE (-5450 4425);
FORCEPROP 2 LAST CDS_LIB pure_quanta_power
J 0
(-5450 4375);
DISPLAY INVISIBLE (-5450 4375);
FORCEPROP 1 LAST PATH I30
J 0
(-5400 4400);
DISPLAY 0.872340 (-5400 4400);
PAINT AQUA (-5400 4400);
DISPLAY INVISIBLE (-5400 4400);
FORCEADD UNIVERSAL_POWER..1
(-5575 5625);
FORCEPROP 3 LASTPIN (-5575 5575) SIG_NAME P3V3_AUX\g
J 0
(-5565 5585);
DISPLAY 0.659574 (-5565 5585);
PAINT MONO (-5565 5585);
DISPLAY INVISIBLE (-5565 5585);
FORCEPROP 1 LAST HDL_POWER P3V3_AUX
J 1
(-5575 5675);
DISPLAY 0.872340 (-5575 5675);
PAINT YELLOW (-5575 5675);
FORCEPROP 2 LAST CDS_LIB pure_quanta_power
J 0
(-5575 5625);
DISPLAY INVISIBLE (-5575 5625);
FORCEPROP 1 LAST PATH I31
J 0
(-5525 5650);
DISPLAY 0.872340 (-5525 5650);
PAINT AQUA (-5525 5650);
DISPLAY INVISIBLE (-5525 5650);
FORCEADD Q_INDUCTOR..1
(-5125 5525);
FORCEPROP 1 LAST LOCATION L2
J 0
(-5250 5685);
DISPLAY 0.723404 (-5250 5685);
PAINT GREEN (-5250 5685);
FORCEPROP 0 LAST $SEC 1
J 0
(-5250 5825);
DISPLAY 0.680851 (-5250 5825);
PAINT MONO (-5250 5825);
DISPLAY INVISIBLE (-5250 5825);
FORCEPROP 0 LAST CDS_SEC 1
J 0
(-5250 5825);
DISPLAY 1.021277 (-5250 5825);
DISPLAY INVISIBLE (-5250 5825);
FORCEPROP 0 LASTPIN (-5225 5500) $PN 1
J 2
(-5235 5510);
DISPLAY 0.680851 (-5235 5510);
PAINT MONO (-5235 5510);
FORCEPROP 0 LASTPIN (-5025 5500) $PN 2
J 0
(-5015 5510);
DISPLAY 0.680851 (-5015 5510);
PAINT MONO (-5015 5510);
FORCEPROP 1 LAST MATERIAL IND
J 0
(-5250 5580);
DISPLAY 0.723404 (-5250 5580);
PAINT GREEN (-5250 5580);
FORCEPROP 2 LAST PACK_TYPE SMLF
J 0
(-5250 5775);
DISPLAY 0.638298 (-5250 5775);
FORCEPROP 2 LAST VALUE FCM2012KF-601T/0.5A
J 0
(-5250 5725);
DISPLAY 0.638298 (-5250 5725);
FORCEPROP 1 LAST NEEDS_NO_SIZE TRUE
J 0
(-5125 5525);
DISPLAY 0.468085 (-5125 5525);
PAINT GREEN (-5125 5525);
DISPLAY INVISIBLE (-5125 5525);
FORCEPROP 2 LAST CDS_LIB pure_quanta
J 0
(-5125 5525);
DISPLAY INVISIBLE (-5125 5525);
FORCEPROP 1 LAST PATH I32
J 0
(-5050 5580);
DISPLAY 0.723404 (-5050 5580);
PAINT GREEN (-5050 5580);
DISPLAY INVISIBLE (-5050 5580);
FORCEPROP 1 LAST PART_NUMBER CX601T05003
J 0
(-5250 5635);
DISPLAY 0.723404 (-5250 5635);
PAINT GREEN (-5250 5635);
DISPLAY INVISIBLE (-5250 5635);
FORCEADD Q_CAP..1
(-4250 5300);
FORCEPROP 1 LAST LOCATION C58
J 0
(-4200 5400);
DISPLAY 0.978723 (-4200 5400);
FORCEPROP 0 LAST $SEC 1
J 0
(-4200 5450);
DISPLAY 0.680851 (-4200 5450);
PAINT MONO (-4200 5450);
DISPLAY INVISIBLE (-4200 5450);
FORCEPROP 0 LAST CDS_SEC 1
J 0
(-4200 5450);
DISPLAY 1.021277 (-4200 5450);
DISPLAY INVISIBLE (-4200 5450);
FORCEPROP 1 LASTPIN (-4250 5400) $PN 1
J 0
(-4240 5380);
DISPLAY 0.787234 (-4240 5380);
PAINT MONO (-4240 5380);
FORCEPROP 1 LASTPIN (-4250 5200) $PN 2
J 0
(-4240 5180);
DISPLAY 0.787234 (-4240 5180);
PAINT MONO (-4240 5180);
FORCEPROP 1 LAST PACK_TYPE 0402
J 0
(-4200 5100);
DISPLAY 0.510638 (-4200 5100);
FORCEPROP 1 LAST MATERIAL X7R
J 0
(-4200 5200);
DISPLAY 0.510638 (-4200 5200);
FORCEPROP 1 LAST VOLTAGE 25V
J 0
(-4200 5300);
DISPLAY 0.510638 (-4200 5300);
FORCEPROP 1 LAST TOLERANCE 10%
J 0
(-4200 5250);
DISPLAY 0.510638 (-4200 5250);
FORCEPROP 1 LAST VALUE 0.1UF
J 0
(-4200 5350);
DISPLAY 0.510638 (-4200 5350);
FORCEPROP 2 LAST CDS_LIB pure_quanta
J 0
(-4250 5300);
DISPLAY INVISIBLE (-4250 5300);
FORCEPROP 1 LAST PATH I34
J 0
(-4200 5450);
DISPLAY 0.978723 (-4200 5450);
PAINT WHITE (-4200 5450);
DISPLAY INVISIBLE (-4200 5450);
FORCEPROP 1 LAST PART_NUMBER CH4104K1B00
J 0
(-4200 5150);
DISPLAY 0.404255 (-4200 5150);
DISPLAY INVISIBLE (-4200 5150);
FORCEADD Q_CAP..1
(-4000 5300);
FORCEPROP 1 LAST LOCATION C90
J 0
(-3950 5400);
DISPLAY 0.978723 (-3950 5400);
FORCEPROP 0 LAST $SEC 1
J 0
(-3950 5450);
DISPLAY 0.680851 (-3950 5450);
PAINT MONO (-3950 5450);
DISPLAY INVISIBLE (-3950 5450);
FORCEPROP 0 LAST CDS_SEC 1
J 0
(-3950 5450);
DISPLAY 1.021277 (-3950 5450);
DISPLAY INVISIBLE (-3950 5450);
FORCEPROP 1 LASTPIN (-4000 5400) $PN 1
J 0
(-3990 5380);
DISPLAY 0.787234 (-3990 5380);
PAINT MONO (-3990 5380);
FORCEPROP 1 LASTPIN (-4000 5200) $PN 2
J 0
(-3990 5180);
DISPLAY 0.787234 (-3990 5180);
PAINT MONO (-3990 5180);
FORCEPROP 1 LAST VOLTAGE 25V
J 0
(-3950 5300);
DISPLAY 0.510638 (-3950 5300);
FORCEPROP 1 LAST PACK_TYPE 0402
J 0
(-3950 5100);
DISPLAY 0.510638 (-3950 5100);
FORCEPROP 1 LAST TOLERANCE 10%
J 0
(-3950 5250);
DISPLAY 0.510638 (-3950 5250);
FORCEPROP 1 LAST MATERIAL X7R
J 0
(-3950 5200);
DISPLAY 0.510638 (-3950 5200);
FORCEPROP 1 LAST VALUE 0.1UF
J 0
(-3950 5350);
DISPLAY 0.510638 (-3950 5350);
FORCEPROP 2 LAST CDS_LIB pure_quanta
J 0
(-4000 5300);
DISPLAY INVISIBLE (-4000 5300);
FORCEPROP 1 LAST PATH I35
J 0
(-3950 5450);
DISPLAY 0.978723 (-3950 5450);
PAINT WHITE (-3950 5450);
DISPLAY INVISIBLE (-3950 5450);
FORCEPROP 1 LAST PART_NUMBER CH4104K1B00
J 0
(-3950 5150);
DISPLAY 0.404255 (-3950 5150);
DISPLAY INVISIBLE (-3950 5150);
FORCEADD Q_CAP..1
(-3750 5300);
FORCEPROP 1 LAST LOCATION C98
J 0
(-3700 5400);
DISPLAY 0.978723 (-3700 5400);
FORCEPROP 0 LAST $SEC 1
J 0
(-3700 5450);
DISPLAY 0.680851 (-3700 5450);
PAINT MONO (-3700 5450);
DISPLAY INVISIBLE (-3700 5450);
FORCEPROP 0 LAST CDS_SEC 1
J 0
(-3700 5450);
DISPLAY 1.021277 (-3700 5450);
DISPLAY INVISIBLE (-3700 5450);
FORCEPROP 1 LASTPIN (-3750 5400) $PN 1
J 0
(-3740 5380);
DISPLAY 0.787234 (-3740 5380);
PAINT MONO (-3740 5380);
FORCEPROP 1 LASTPIN (-3750 5200) $PN 2
J 0
(-3740 5180);
DISPLAY 0.787234 (-3740 5180);
PAINT MONO (-3740 5180);
FORCEPROP 1 LAST MATERIAL X7R
J 0
(-3700 5200);
DISPLAY 0.510638 (-3700 5200);
FORCEPROP 1 LAST PACK_TYPE 0402
J 0
(-3700 5100);
DISPLAY 0.510638 (-3700 5100);
FORCEPROP 1 LAST TOLERANCE 10%
J 0
(-3700 5250);
DISPLAY 0.510638 (-3700 5250);
FORCEPROP 1 LAST VOLTAGE 25V
J 0
(-3700 5300);
DISPLAY 0.510638 (-3700 5300);
FORCEPROP 1 LAST VALUE 0.1UF
J 0
(-3700 5350);
DISPLAY 0.510638 (-3700 5350);
FORCEPROP 2 LAST CDS_LIB pure_quanta
J 0
(-3750 5300);
DISPLAY INVISIBLE (-3750 5300);
FORCEPROP 1 LAST PATH I36
J 0
(-3700 5450);
DISPLAY 0.978723 (-3700 5450);
PAINT WHITE (-3700 5450);
DISPLAY INVISIBLE (-3700 5450);
FORCEPROP 1 LAST PART_NUMBER CH4104K1B00
J 0
(-3700 5150);
DISPLAY 0.404255 (-3700 5150);
DISPLAY INVISIBLE (-3700 5150);
FORCEADD OFFPAGE..2
(-3200 1350);
FORCEPROP 2 LAST $XR0 183 
J 0
(-3011 1350);
DISPLAY 0.638298 (-3011 1350);
PAINT MONO (-3011 1350);
FORCEPROP 2 LAST CDS_LIB standard
J 0
(-3200 1350);
DISPLAY INVISIBLE (-3200 1350);
FORCEPROP 1 LAST OFFPAGE TRUE
J 0
(-2875 1225);
DISPLAY 0.872340 (-2875 1225);
DISPLAY INVISIBLE (-2875 1225);
FORCEPROP 1 LAST COMMENT_BODY TRUE
J 0
(-3245 1255);
DISPLAY 0.872340 (-3245 1255);
PAINT GREEN (-3245 1255);
DISPLAY INVISIBLE (-3245 1255);
FORCEPROP 2 LAST PATH I37
J 0
(-3000 1400);
DISPLAY 0.680851 (-3000 1400);
DISPLAY INVISIBLE (-3000 1400);
FORCEADD UNIVERSAL_GND..1
(-3700 2550);
FORCEPROP 3 LASTPIN (-3700 2600) SIG_NAME GND\g
J 0
(-3690 2610);
DISPLAY 0.659574 (-3690 2610);
PAINT MONO (-3690 2610);
DISPLAY INVISIBLE (-3690 2610);
FORCEPROP 2 LAST CDS_LIB pure_quanta_power
J 0
(-3700 2550);
DISPLAY INVISIBLE (-3700 2550);
FORCEPROP 1 LAST HDL_POWER GND
J 1
(-3675 2475);
DISPLAY 0.872340 (-3675 2475);
PAINT GREEN (-3675 2475);
DISPLAY INVISIBLE (-3675 2475);
FORCEPROP 1 LAST PATH I38
J 0
(-3625 2550);
DISPLAY 0.872340 (-3625 2550);
PAINT AQUA (-3625 2550);
DISPLAY INVISIBLE (-3625 2550);
FORCEADD Q_RES..2
(-2550 2775);
FORCEPROP 1 LAST LOCATION R592
J 0
(-2505 2900);
DISPLAY 0.638298 (-2505 2900);
FORCEPROP 0 LAST $SEC 1
J 0
(-2500 2950);
DISPLAY 0.680851 (-2500 2950);
PAINT MONO (-2500 2950);
DISPLAY INVISIBLE (-2500 2950);
FORCEPROP 0 LAST CDS_SEC 1
J 0
(-2500 2950);
DISPLAY 1.021277 (-2500 2950);
DISPLAY INVISIBLE (-2500 2950);
FORCEPROP 1 LASTPIN (-2550 2875) $PN 1
J 0
(-2545 2837);
DISPLAY 0.787234 (-2545 2837);
PAINT MONO (-2545 2837);
FORCEPROP 1 LASTPIN (-2550 2675) $PN 2
J 0
(-2545 2685);
DISPLAY 0.787234 (-2545 2685);
PAINT MONO (-2545 2685);
FORCEPROP 1 LAST PACK_TYPE 0402LF
J 0
(-2500 2650);
DISPLAY 0.510638 (-2500 2650);
FORCEPROP 1 LAST MATERIAL CHIP
J 0
(-2510 2700);
DISPLAY 0.510638 (-2510 2700);
FORCEPROP 1 LAST VALUE 10K
J 0
(-2505 2850);
DISPLAY 0.510638 (-2505 2850);
FORCEPROP 1 LAST TOLERANCE 1%
J 0
(-2505 2800);
DISPLAY 0.510638 (-2505 2800);
FORCEPROP 1 LAST WATTAGE 1/16W
J 0
(-2510 2750);
DISPLAY 0.510638 (-2510 2750);
FORCEPROP 2 LAST CDS_LIB pure_quanta
J 0
(-2550 2775);
DISPLAY INVISIBLE (-2550 2775);
FORCEPROP 1 LAST PATH I49
J 0
(-2500 2950);
DISPLAY 0.978723 (-2500 2950);
PAINT WHITE (-2500 2950);
DISPLAY INVISIBLE (-2500 2950);
FORCEPROP 1 LAST PART_NUMBER CS31002FB08
J 0
(-2510 2650);
DISPLAY 0.510638 (-2510 2650);
DISPLAY INVISIBLE (-2510 2650);
FORCEADD Q_RES..2
(-2350 2775);
FORCEPROP 1 LAST LOCATION R593
J 0
(-2305 2900);
DISPLAY 0.638298 (-2305 2900);
FORCEPROP 0 LAST $SEC 1
J 0
(-2300 2950);
DISPLAY 0.680851 (-2300 2950);
PAINT MONO (-2300 2950);
DISPLAY INVISIBLE (-2300 2950);
FORCEPROP 0 LAST CDS_SEC 1
J 0
(-2300 2950);
DISPLAY 1.021277 (-2300 2950);
DISPLAY INVISIBLE (-2300 2950);
FORCEPROP 1 LASTPIN (-2350 2875) $PN 1
J 0
(-2345 2837);
DISPLAY 0.787234 (-2345 2837);
PAINT MONO (-2345 2837);
FORCEPROP 1 LASTPIN (-2350 2675) $PN 2
J 0
(-2345 2685);
DISPLAY 0.787234 (-2345 2685);
PAINT MONO (-2345 2685);
FORCEPROP 1 LAST MATERIAL CHIP
J 0
(-2310 2700);
DISPLAY 0.510638 (-2310 2700);
FORCEPROP 1 LAST PACK_TYPE 0402LF
J 0
(-2300 2650);
DISPLAY 0.510638 (-2300 2650);
FORCEPROP 1 LAST TOLERANCE 1%
J 0
(-2305 2800);
DISPLAY 0.510638 (-2305 2800);
FORCEPROP 1 LAST WATTAGE 1/16W
J 0
(-2310 2750);
DISPLAY 0.510638 (-2310 2750);
FORCEPROP 1 LAST VALUE 10K
J 0
(-2305 2850);
DISPLAY 0.510638 (-2305 2850);
FORCEPROP 2 LAST CDS_LIB pure_quanta
J 0
(-2350 2775);
DISPLAY INVISIBLE (-2350 2775);
FORCEPROP 1 LAST PATH I50
J 0
(-2300 2950);
DISPLAY 0.978723 (-2300 2950);
PAINT WHITE (-2300 2950);
DISPLAY INVISIBLE (-2300 2950);
FORCEPROP 1 LAST PART_NUMBER CS31002FB08
J 0
(-2310 2650);
DISPLAY 0.510638 (-2310 2650);
DISPLAY INVISIBLE (-2310 2650);
FORCEADD Q_RES..2
(-2125 2775);
FORCEPROP 1 LAST LOCATION R594
J 0
(-2080 2900);
DISPLAY 0.638298 (-2080 2900);
FORCEPROP 0 LAST $SEC 1
J 0
(-2075 2950);
DISPLAY 0.680851 (-2075 2950);
PAINT MONO (-2075 2950);
DISPLAY INVISIBLE (-2075 2950);
FORCEPROP 0 LAST CDS_SEC 1
J 0
(-2075 2950);
DISPLAY 1.021277 (-2075 2950);
DISPLAY INVISIBLE (-2075 2950);
FORCEPROP 1 LASTPIN (-2125 2875) $PN 1
J 0
(-2120 2837);
DISPLAY 0.787234 (-2120 2837);
PAINT MONO (-2120 2837);
FORCEPROP 1 LASTPIN (-2125 2675) $PN 2
J 0
(-2120 2685);
DISPLAY 0.787234 (-2120 2685);
PAINT MONO (-2120 2685);
FORCEPROP 1 LAST PACK_TYPE 0402LF
J 0
(-2085 2600);
DISPLAY 0.510638 (-2085 2600);
FORCEPROP 1 LAST MATERIAL CHIP
J 0
(-2085 2700);
DISPLAY 0.510638 (-2085 2700);
FORCEPROP 1 LAST VALUE 10K
J 0
(-2080 2850);
DISPLAY 0.510638 (-2080 2850);
FORCEPROP 1 LAST WATTAGE 1/16W
J 0
(-2085 2750);
DISPLAY 0.510638 (-2085 2750);
FORCEPROP 1 LAST TOLERANCE 1%
J 0
(-2080 2800);
DISPLAY 0.510638 (-2080 2800);
FORCEPROP 2 LAST CDS_LIB pure_quanta
J 0
(-2125 2775);
DISPLAY INVISIBLE (-2125 2775);
FORCEPROP 1 LAST PATH I51
J 0
(-2075 2950);
DISPLAY 0.978723 (-2075 2950);
PAINT WHITE (-2075 2950);
DISPLAY INVISIBLE (-2075 2950);
FORCEPROP 1 LAST PART_NUMBER CS31002FB08
J 0
(-2085 2650);
DISPLAY 0.510638 (-2085 2650);
DISPLAY INVISIBLE (-2085 2650);
FORCEADD UNIVERSAL_POWER..1
(-3575 4375);
FORCEPROP 3 LASTPIN (-3575 4325) SIG_NAME P3V3_9ZXL045_P1_VDDA\g
J 0
(-3565 4335);
DISPLAY 0.659574 (-3565 4335);
PAINT MONO (-3565 4335);
DISPLAY INVISIBLE (-3565 4335);
FORCEPROP 1 LAST HDL_POWER P3V3_9ZXL045_P1_VDDA
J 1
(-3575 4425);
DISPLAY 0.872340 (-3575 4425);
PAINT SKYBLUE (-3575 4425);
FORCEPROP 2 LAST CDS_LIB pure_quanta_power
J 0
(-3575 4375);
DISPLAY INVISIBLE (-3575 4375);
FORCEPROP 1 LAST PATH I56
J 0
(-3525 4400);
DISPLAY 0.872340 (-3525 4400);
PAINT AQUA (-3525 4400);
DISPLAY INVISIBLE (-3525 4400);
FORCEADD OFFPAGE..1
R 2
(-3025 3950);
FORCEPROP 2 LAST $XR0 183 
J 0
(-2839 3950);
DISPLAY 0.638298 (-2839 3950);
PAINT MONO (-2839 3950);
FORCEPROP 2 LAST CDS_LIB standard
J 2
(-3025 3950);
DISPLAY INVISIBLE (-3025 3950);
FORCEPROP 1 LAST OFFPAGE TRUE
J 2
(-3350 3825);
DISPLAY 1.170213 (-3350 3825);
PAINT GREEN (-3350 3825);
DISPLAY INVISIBLE (-3350 3825);
FORCEPROP 1 LAST COMMENT_BODY TRUE
J 2
(-3150 3850);
DISPLAY 1.170213 (-3150 3850);
PAINT GREEN (-3150 3850);
DISPLAY INVISIBLE (-3150 3850);
FORCEPROP 2 LAST PATH I57
J 0
(-2825 4000);
DISPLAY 0.680851 (-2825 4000);
DISPLAY INVISIBLE (-2825 4000);
FORCEADD Q_CAP..1
(-3500 5300);
FORCEPROP 1 LAST LOCATION C99
J 0
(-3450 5400);
DISPLAY 0.978723 (-3450 5400);
FORCEPROP 0 LAST $SEC 1
J 0
(-3450 5450);
DISPLAY 0.680851 (-3450 5450);
PAINT MONO (-3450 5450);
DISPLAY INVISIBLE (-3450 5450);
FORCEPROP 0 LAST CDS_SEC 1
J 0
(-3450 5450);
DISPLAY 1.021277 (-3450 5450);
DISPLAY INVISIBLE (-3450 5450);
FORCEPROP 1 LASTPIN (-3500 5400) $PN 1
J 0
(-3490 5380);
DISPLAY 0.787234 (-3490 5380);
PAINT MONO (-3490 5380);
FORCEPROP 1 LASTPIN (-3500 5200) $PN 2
J 0
(-3490 5180);
DISPLAY 0.787234 (-3490 5180);
PAINT MONO (-3490 5180);
FORCEPROP 1 LAST MATERIAL X7R
J 0
(-3450 5200);
DISPLAY 0.510638 (-3450 5200);
FORCEPROP 1 LAST TOLERANCE 10%
J 0
(-3450 5250);
DISPLAY 0.510638 (-3450 5250);
FORCEPROP 1 LAST VOLTAGE 25V
J 0
(-3450 5300);
DISPLAY 0.510638 (-3450 5300);
FORCEPROP 1 LAST PACK_TYPE 0402
J 0
(-3450 5100);
DISPLAY 0.510638 (-3450 5100);
FORCEPROP 1 LAST VALUE 0.1UF
J 0
(-3450 5350);
DISPLAY 0.510638 (-3450 5350);
FORCEPROP 2 LAST CDS_LIB pure_quanta
J 0
(-3500 5300);
DISPLAY INVISIBLE (-3500 5300);
FORCEPROP 1 LAST PATH I58
J 0
(-3450 5450);
DISPLAY 0.978723 (-3450 5450);
PAINT WHITE (-3450 5450);
DISPLAY INVISIBLE (-3450 5450);
FORCEPROP 1 LAST PART_NUMBER CH4104K1B00
J 0
(-3450 5150);
DISPLAY 0.404255 (-3450 5150);
DISPLAY INVISIBLE (-3450 5150);
FORCEADD UNIVERSAL_GND..1
(-3225 4950);
FORCEPROP 3 LASTPIN (-3225 5000) SIG_NAME GND\g
J 0
(-3215 5010);
DISPLAY 0.659574 (-3215 5010);
PAINT MONO (-3215 5010);
DISPLAY INVISIBLE (-3215 5010);
FORCEPROP 2 LAST CDS_LIB pure_quanta_power
J 0
(-3225 4950);
DISPLAY INVISIBLE (-3225 4950);
FORCEPROP 1 LAST HDL_POWER GND
J 1
(-3200 4875);
DISPLAY 0.872340 (-3200 4875);
PAINT GREEN (-3200 4875);
DISPLAY INVISIBLE (-3200 4875);
FORCEPROP 1 LAST PATH I59
J 0
(-3150 4950);
DISPLAY 0.872340 (-3150 4950);
PAINT AQUA (-3150 4950);
DISPLAY INVISIBLE (-3150 4950);
FORCEADD Q_CAP..1
(-3225 5300);
FORCEPROP 1 LAST LOCATION C75
J 0
(-3175 5400);
DISPLAY 0.978723 (-3175 5400);
FORCEPROP 2 LAST $SEC 1
J 0
(-3175 5500);
DISPLAY 0.680851 (-3175 5500);
PAINT MONO (-3175 5500);
DISPLAY INVISIBLE (-3175 5500);
FORCEPROP 2 LAST CDS_SEC 1
J 0
(-3175 5500);
DISPLAY 1.021277 (-3175 5500);
DISPLAY INVISIBLE (-3175 5500);
FORCEPROP 1 LASTPIN (-3225 5400) $PN 1
J 0
(-3215 5380);
DISPLAY 0.787234 (-3215 5380);
PAINT MONO (-3215 5380);
FORCEPROP 1 LASTPIN (-3225 5200) $PN 2
J 0
(-3215 5180);
DISPLAY 0.787234 (-3215 5180);
PAINT MONO (-3215 5180);
FORCEPROP 1 LAST PACK_TYPE 0402
J 0
(-3175 5100);
DISPLAY 0.510638 (-3175 5100);
FORCEPROP 1 LAST MATERIAL X7R
J 0
(-3175 5200);
DISPLAY 0.510638 (-3175 5200);
FORCEPROP 1 LAST TOLERANCE 10%
J 0
(-3175 5250);
DISPLAY 0.510638 (-3175 5250);
FORCEPROP 1 LAST VALUE 0.1UF
J 0
(-3175 5350);
DISPLAY 0.510638 (-3175 5350);
FORCEPROP 1 LAST VOLTAGE 25V
J 0
(-3175 5300);
DISPLAY 0.510638 (-3175 5300);
FORCEPROP 2 LAST CDS_LIB pure_quanta
J 0
(-3225 5300);
DISPLAY INVISIBLE (-3225 5300);
FORCEPROP 1 LAST PATH I60
J 0
(-3175 5450);
DISPLAY 0.978723 (-3175 5450);
PAINT WHITE (-3175 5450);
DISPLAY INVISIBLE (-3175 5450);
FORCEPROP 1 LAST PART_NUMBER CH4104K1B00
J 0
(-3175 5150);
DISPLAY 0.404255 (-3175 5150);
DISPLAY INVISIBLE (-3175 5150);
FORCEADD UNIVERSAL_POWER..1
(-3225 5650);
FORCEPROP 3 LASTPIN (-3225 5600) SIG_NAME P3V3_9ZXL045_P1_VDD\g
J 0
(-3215 5610);
DISPLAY 0.659574 (-3215 5610);
PAINT MONO (-3215 5610);
DISPLAY INVISIBLE (-3215 5610);
FORCEPROP 1 LAST HDL_POWER P3V3_9ZXL045_P1_VDD
J 1
(-3225 5700);
DISPLAY 0.872340 (-3225 5700);
PAINT SKYBLUE (-3225 5700);
FORCEPROP 2 LAST CDS_LIB pure_quanta_power
J 0
(-3225 5650);
DISPLAY INVISIBLE (-3225 5650);
FORCEPROP 1 LAST PATH I61
J 0
(-3175 5675);
DISPLAY 0.872340 (-3175 5675);
PAINT AQUA (-3175 5675);
DISPLAY INVISIBLE (-3175 5675);
FORCEADD 9ZXL0451EKILFT..1
(-4525 3475);
FORCEPROP 1 LAST LOCATION U10
J 0
(-4991 4490);
DISPLAY 0.723404 (-4991 4490);
PAINT GREEN (-4991 4490);
FORCEPROP 0 LAST $SEC 1
J 0
(-4975 4625);
DISPLAY 0.680851 (-4975 4625);
PAINT MONO (-4975 4625);
DISPLAY INVISIBLE (-4975 4625);
FORCEPROP 0 LAST CDS_SEC 1
J 0
(-4975 4625);
DISPLAY 1.021277 (-4975 4625);
DISPLAY INVISIBLE (-4975 4625);
FORCEPROP 0 LASTPIN (-5150 3250) $PN 1
J 2
(-5160 3260);
DISPLAY 0.680851 (-5160 3260);
PAINT MONO (-5160 3260);
FORCEPROP 0 LASTPIN (-3900 3950) $PN 32
J 0
(-3890 3960);
DISPLAY 0.680851 (-3890 3960);
PAINT MONO (-3890 3960);
FORCEPROP 0 LASTPIN (-3900 3750) $PN 13
J 0
(-3890 3760);
DISPLAY 0.680851 (-3890 3760);
PAINT MONO (-3890 3760);
FORCEPROP 0 LASTPIN (-3900 3700) $PN 14
J 0
(-3890 3710);
DISPLAY 0.680851 (-3890 3710);
PAINT MONO (-3890 3710);
FORCEPROP 0 LASTPIN (-3900 3650) $PN 19
J 0
(-3890 3660);
DISPLAY 0.680851 (-3890 3660);
PAINT MONO (-3890 3660);
FORCEPROP 0 LASTPIN (-3900 3600) $PN 20
J 0
(-3890 3610);
DISPLAY 0.680851 (-3890 3610);
PAINT MONO (-3890 3610);
FORCEPROP 0 LASTPIN (-3900 3550) $PN 22
J 0
(-3890 3560);
DISPLAY 0.680851 (-3890 3560);
PAINT MONO (-3890 3560);
FORCEPROP 0 LASTPIN (-3900 3500) $PN 23
J 0
(-3890 3510);
DISPLAY 0.680851 (-3890 3510);
PAINT MONO (-3890 3510);
FORCEPROP 0 LASTPIN (-3900 3450) $PN 27
J 0
(-3890 3460);
DISPLAY 0.680851 (-3890 3460);
PAINT MONO (-3890 3460);
FORCEPROP 0 LASTPIN (-3900 3400) $PN 28
J 0
(-3890 3410);
DISPLAY 0.680851 (-3890 3410);
PAINT MONO (-3890 3410);
FORCEPROP 0 LASTPIN (-5150 3650) $PN 3
J 2
(-5160 3660);
DISPLAY 0.680851 (-5160 3660);
PAINT MONO (-5160 3660);
FORCEPROP 0 LASTPIN (-5150 3600) $PN 4
J 2
(-5160 3610);
DISPLAY 0.680851 (-5160 3610);
PAINT MONO (-5160 3610);
FORCEPROP 0 LASTPIN (-3900 2850) $PN 33
J 0
(-3890 2860);
DISPLAY 0.680851 (-3890 2860);
PAINT MONO (-3890 2860);
FORCEPROP 0 LASTPIN (-5150 3200) $PN 9
J 2
(-5160 3210);
DISPLAY 0.680851 (-5160 3210);
PAINT MONO (-5160 3210);
FORCEPROP 0 LASTPIN (-5150 3150) $PN 8
J 2
(-5160 3160);
DISPLAY 0.680851 (-5160 3160);
PAINT MONO (-5160 3160);
FORCEPROP 0 LASTPIN (-5150 3000) $PN 10
J 2
(-5160 3010);
DISPLAY 0.680851 (-5160 3010);
PAINT MONO (-5160 3010);
FORCEPROP 0 LASTPIN (-5150 2950) $PN 11
J 2
(-5160 2960);
DISPLAY 0.680851 (-5160 2960);
PAINT MONO (-5160 2960);
FORCEPROP 0 LASTPIN (-5150 2900) $PN 17
J 2
(-5160 2910);
DISPLAY 0.680851 (-5160 2910);
PAINT MONO (-5160 2910);
FORCEPROP 0 LASTPIN (-5150 2850) $PN 30
J 2
(-5160 2860);
DISPLAY 0.680851 (-5160 2860);
PAINT MONO (-5160 2860);
FORCEPROP 0 LASTPIN (-5150 3350) $PN 7
J 2
(-5160 3360);
DISPLAY 0.680851 (-5160 3360);
PAINT MONO (-5160 3360);
FORCEPROP 0 LASTPIN (-5150 3400) $PN 6
J 2
(-5160 3410);
DISPLAY 0.680851 (-5160 3410);
PAINT MONO (-5160 3410);
FORCEPROP 0 LASTPIN (-5150 4100) $PN 12
J 2
(-5160 4110);
DISPLAY 0.680851 (-5160 4110);
PAINT MONO (-5160 4110);
FORCEPROP 0 LASTPIN (-5150 4050) $PN 16
J 2
(-5160 4060);
DISPLAY 0.680851 (-5160 4060);
PAINT MONO (-5160 4060);
FORCEPROP 0 LASTPIN (-5150 4000) $PN 21
J 2
(-5160 4010);
DISPLAY 0.680851 (-5160 4010);
PAINT MONO (-5160 4010);
FORCEPROP 0 LASTPIN (-5150 3950) $PN 25
J 2
(-5160 3960);
DISPLAY 0.680851 (-5160 3960);
PAINT MONO (-5160 3960);
FORCEPROP 0 LASTPIN (-5150 3900) $PN 29
J 2
(-5160 3910);
DISPLAY 0.680851 (-5160 3910);
PAINT MONO (-5160 3910);
FORCEPROP 0 LASTPIN (-3900 4100) $PN 31
J 0
(-3890 4110);
DISPLAY 0.680851 (-3890 4110);
PAINT MONO (-3890 4110);
FORCEPROP 0 LASTPIN (-5150 3800) $PN 2
J 2
(-5160 3810);
DISPLAY 0.680851 (-5160 3810);
PAINT MONO (-5160 3810);
FORCEPROP 0 LASTPIN (-3900 3200) $PN 15
J 0
(-3890 3210);
DISPLAY 0.680851 (-3890 3210);
PAINT MONO (-3890 3210);
FORCEPROP 0 LASTPIN (-3900 3150) $PN 18
J 0
(-3890 3160);
DISPLAY 0.680851 (-3890 3160);
PAINT MONO (-3890 3160);
FORCEPROP 0 LASTPIN (-3900 3100) $PN 24
J 0
(-3890 3110);
DISPLAY 0.680851 (-3890 3110);
PAINT MONO (-3890 3110);
FORCEPROP 0 LASTPIN (-3900 3050) $PN 26
J 0
(-3890 3060);
DISPLAY 0.680851 (-3890 3060);
PAINT MONO (-3890 3060);
FORCEPROP 0 LASTPIN (-5150 3500) $PN 5
J 2
(-5160 3510);
DISPLAY 0.680851 (-5160 3510);
PAINT MONO (-5160 3510);
FORCEPROP 2 LAST VALUE 9ZXL0451EKILFT
J 0
(-4975 4525);
DISPLAY 1.021277 (-4975 4525);
FORCEPROP 1 LAST MATERIAL IC
J 0
(-4991 4216);
DISPLAY 0.723404 (-4991 4216);
PAINT GREEN (-4991 4216);
FORCEPROP 2 LAST PART_TYPE SMLF
J 0
(-4975 4575);
DISPLAY 1.021277 (-4975 4575);
FORCEPROP 2 LAST CDS_LIB pure_quanta
J 0
(-4525 3475);
DISPLAY INVISIBLE (-4525 3475);
FORCEPROP 1 LAST NEEDS_NO_SIZE TRUE
J 0
(-4525 3475);
DISPLAY 0.723404 (-4525 3475);
PAINT GREEN (-4525 3475);
DISPLAY INVISIBLE (-4525 3475);
FORCEPROP 1 LAST CDS_LMAN_SYM_OUTLINE -475,725,475,-725
J 0
(-4525 3475);
DISPLAY 0.468085 (-4525 3475);
PAINT GREEN (-4525 3475);
DISPLAY INVISIBLE (-4525 3475);
FORCEPROP 1 LAST PATH I63
J 0
(-4525 3475);
DISPLAY 0.723404 (-4525 3475);
PAINT GREEN (-4525 3475);
DISPLAY INVISIBLE (-4525 3475);
FORCEPROP 1 LAST PART_NUMBER AL000451003
J 0
(-4991 4343);
DISPLAY 0.723404 (-4991 4343);
PAINT GREEN (-4991 4343);
DISPLAY INVISIBLE (-4991 4343);
FORCEADD Q_RES..2
(-5925 1150);
FORCEPROP 1 LAST LOCATION R579
J 0
(-5880 1275);
DISPLAY 0.978723 (-5880 1275);
FORCEPROP 0 LAST $SEC 1
J 0
(-5875 1325);
DISPLAY 0.680851 (-5875 1325);
PAINT MONO (-5875 1325);
DISPLAY INVISIBLE (-5875 1325);
FORCEPROP 0 LAST CDS_SEC 1
J 0
(-5875 1325);
DISPLAY 0.680851 (-5875 1325);
DISPLAY INVISIBLE (-5875 1325);
FORCEPROP 1 LASTPIN (-5925 1250) $PN 1
J 0
(-5920 1212);
DISPLAY 0.787234 (-5920 1212);
PAINT MONO (-5920 1212);
FORCEPROP 1 LASTPIN (-5925 1050) $PN 2
J 0
(-5920 1060);
DISPLAY 0.787234 (-5920 1060);
PAINT MONO (-5920 1060);
FORCEPROP 1 LAST TOLERANCE 1%
J 0
(-5880 1175);
DISPLAY 0.638298 (-5880 1175);
FORCEPROP 1 LAST PACK_TYPE 0402LF
J 0
(-5885 1025);
DISPLAY 0.638298 (-5885 1025);
FORCEPROP 1 LAST VALUE 4.75K
J 0
(-5880 1225);
DISPLAY 0.638298 (-5880 1225);
FORCEPROP 1 LAST WATTAGE 1/16W
J 0
(-5885 1125);
DISPLAY 0.638298 (-5885 1125);
FORCEPROP 1 LAST MATERIAL CHIP
J 0
(-5885 1075);
DISPLAY 0.638298 (-5885 1075);
FORCEPROP 2 LAST CDS_LIB pure_quanta
J 0
(-5925 1150);
DISPLAY INVISIBLE (-5925 1150);
FORCEPROP 1 LAST PATH I64
J 0
(-5875 1325);
DISPLAY 0.978723 (-5875 1325);
PAINT WHITE (-5875 1325);
DISPLAY INVISIBLE (-5875 1325);
FORCEPROP 1 LAST PART_NUMBER CS24752FB03
J 0
(-5885 1025);
DISPLAY 0.638298 (-5885 1025);
DISPLAY INVISIBLE (-5885 1025);
FORCEADD Q_RES..2
(-5925 1575);
FORCEPROP 1 LAST LOCATION R578
J 0
(-5880 1700);
DISPLAY 0.978723 (-5880 1700);
FORCEPROP 0 LAST $SEC 1
J 0
(-5875 1750);
DISPLAY 0.680851 (-5875 1750);
PAINT MONO (-5875 1750);
DISPLAY INVISIBLE (-5875 1750);
FORCEPROP 0 LAST CDS_SEC 1
J 0
(-5875 1750);
DISPLAY 0.680851 (-5875 1750);
DISPLAY INVISIBLE (-5875 1750);
FORCEPROP 1 LASTPIN (-5925 1675) $PN 1
J 0
(-5920 1637);
DISPLAY 0.787234 (-5920 1637);
PAINT MONO (-5920 1637);
FORCEPROP 1 LASTPIN (-5925 1475) $PN 2
J 0
(-5920 1485);
DISPLAY 0.787234 (-5920 1485);
PAINT MONO (-5920 1485);
FORCEPROP 1 LAST WATTAGE 1/16W
J 0
(-5885 1550);
DISPLAY 0.638298 (-5885 1550);
FORCEPROP 1 LAST VALUE 4.75K
J 0
(-5880 1650);
DISPLAY 0.638298 (-5880 1650);
FORCEPROP 1 LAST MATERIAL EMPTY
J 0
(-5885 1500);
DISPLAY 0.638298 (-5885 1500);
PAINT RED (-5885 1500);
FORCEPROP 1 LAST TOLERANCE 1%
J 0
(-5880 1600);
DISPLAY 0.638298 (-5880 1600);
FORCEPROP 1 LAST PACK_TYPE 0402LF
J 0
(-5885 1450);
DISPLAY 0.638298 (-5885 1450);
FORCEPROP 2 LAST CDS_LIB pure_quanta
J 0
(-5925 1575);
DISPLAY INVISIBLE (-5925 1575);
FORCEPROP 1 LAST PATH I65
J 0
(-5875 1750);
DISPLAY 0.978723 (-5875 1750);
PAINT WHITE (-5875 1750);
DISPLAY INVISIBLE (-5875 1750);
FORCEPROP 1 LAST PART_NUMBER CS24752FB03
J 0
(-5885 1450);
DISPLAY 0.638298 (-5885 1450);
DISPLAY INVISIBLE (-5885 1450);
FORCEADD OFFPAGE..2
(-2525 3400);
FORCEPROP 2 LAST $XR0 354 
J 0
(-2336 3400);
DISPLAY 0.638298 (-2336 3400);
PAINT MONO (-2336 3400);
FORCEPROP 2 LAST CDS_LIB standard
J 0
(-2525 3400);
DISPLAY INVISIBLE (-2525 3400);
FORCEPROP 1 LAST OFFPAGE TRUE
J 0
(-2200 3275);
DISPLAY 0.872340 (-2200 3275);
PAINT GREEN (-2200 3275);
DISPLAY INVISIBLE (-2200 3275);
FORCEPROP 1 LAST COMMENT_BODY TRUE
J 0
(-2570 3305);
DISPLAY 0.872340 (-2570 3305);
PAINT GREEN (-2570 3305);
DISPLAY INVISIBLE (-2570 3305);
FORCEPROP 2 LAST PATH I66
J 0
(-2350 3475);
DISPLAY 0.680851 (-2350 3475);
DISPLAY INVISIBLE (-2350 3475);
FORCEADD OFFPAGE..2
(-2525 3450);
FORCEPROP 2 LAST $XR0 354 
J 0
(-2336 3450);
DISPLAY 0.638298 (-2336 3450);
PAINT MONO (-2336 3450);
FORCEPROP 2 LAST CDS_LIB standard
J 0
(-2525 3450);
DISPLAY INVISIBLE (-2525 3450);
FORCEPROP 1 LAST OFFPAGE TRUE
J 0
(-2200 3325);
DISPLAY 0.872340 (-2200 3325);
PAINT GREEN (-2200 3325);
DISPLAY INVISIBLE (-2200 3325);
FORCEPROP 1 LAST COMMENT_BODY TRUE
J 0
(-2570 3355);
DISPLAY 0.872340 (-2570 3355);
PAINT GREEN (-2570 3355);
DISPLAY INVISIBLE (-2570 3355);
FORCEPROP 2 LAST PATH I67
J 0
(-2350 3525);
DISPLAY 0.680851 (-2350 3525);
DISPLAY INVISIBLE (-2350 3525);
FORCEADD OFFPAGE..2
(-2525 3500);
FORCEPROP 2 LAST $XR0 343 
J 0
(-2336 3500);
DISPLAY 0.638298 (-2336 3500);
PAINT MONO (-2336 3500);
FORCEPROP 2 LAST CDS_LIB standard
J 0
(-2525 3500);
DISPLAY INVISIBLE (-2525 3500);
FORCEPROP 1 LAST OFFPAGE TRUE
J 0
(-2200 3375);
DISPLAY 0.872340 (-2200 3375);
PAINT GREEN (-2200 3375);
DISPLAY INVISIBLE (-2200 3375);
FORCEPROP 1 LAST COMMENT_BODY TRUE
J 0
(-2570 3405);
DISPLAY 0.872340 (-2570 3405);
PAINT GREEN (-2570 3405);
DISPLAY INVISIBLE (-2570 3405);
FORCEPROP 2 LAST PATH I68
J 0
(-2325 3550);
DISPLAY 0.680851 (-2325 3550);
DISPLAY INVISIBLE (-2325 3550);
FORCEADD OFFPAGE..2
(-2525 3550);
FORCEPROP 2 LAST $XR0 343 
J 0
(-2336 3550);
DISPLAY 0.638298 (-2336 3550);
PAINT MONO (-2336 3550);
FORCEPROP 2 LAST CDS_LIB standard
J 0
(-2525 3550);
DISPLAY INVISIBLE (-2525 3550);
FORCEPROP 1 LAST OFFPAGE TRUE
J 0
(-2200 3425);
DISPLAY 0.872340 (-2200 3425);
PAINT GREEN (-2200 3425);
DISPLAY INVISIBLE (-2200 3425);
FORCEPROP 1 LAST COMMENT_BODY TRUE
J 0
(-2570 3455);
DISPLAY 0.872340 (-2570 3455);
PAINT GREEN (-2570 3455);
DISPLAY INVISIBLE (-2570 3455);
FORCEPROP 2 LAST PATH I69
J 0
(-2325 3600);
DISPLAY 0.680851 (-2325 3600);
DISPLAY INVISIBLE (-2325 3600);
FORCEADD UNIVERSAL_POWER..1
(-5925 1925);
FORCEPROP 3 LASTPIN (-5925 1875) SIG_NAME P3V3_AUX\g
J 0
(-5915 1885);
DISPLAY 0.659574 (-5915 1885);
PAINT MONO (-5915 1885);
DISPLAY INVISIBLE (-5915 1885);
FORCEPROP 1 LAST HDL_POWER P3V3_AUX
J 1
(-5925 1975);
DISPLAY 0.872340 (-5925 1975);
PAINT YELLOW (-5925 1975);
FORCEPROP 2 LAST CDS_LIB pure_quanta_power
J 0
(-5925 1925);
DISPLAY INVISIBLE (-5925 1925);
FORCEPROP 1 LAST PATH I7
J 0
(-5875 1950);
DISPLAY 0.872340 (-5875 1950);
PAINT AQUA (-5875 1950);
DISPLAY INVISIBLE (-5875 1950);
FORCEADD OFFPAGE..2
(-2525 3600);
FORCEPROP 2 LAST $XR0 332 
J 0
(-2336 3600);
DISPLAY 0.638298 (-2336 3600);
PAINT MONO (-2336 3600);
FORCEPROP 2 LAST CDS_LIB standard
J 0
(-2525 3600);
DISPLAY INVISIBLE (-2525 3600);
FORCEPROP 1 LAST OFFPAGE TRUE
J 0
(-2200 3475);
DISPLAY 0.872340 (-2200 3475);
PAINT GREEN (-2200 3475);
DISPLAY INVISIBLE (-2200 3475);
FORCEPROP 1 LAST COMMENT_BODY TRUE
J 0
(-2570 3505);
DISPLAY 0.872340 (-2570 3505);
PAINT GREEN (-2570 3505);
DISPLAY INVISIBLE (-2570 3505);
FORCEPROP 2 LAST PATH I70
J 0
(-2325 3650);
DISPLAY 0.680851 (-2325 3650);
DISPLAY INVISIBLE (-2325 3650);
FORCEADD OFFPAGE..2
(-2525 3750);
FORCEPROP 2 LAST $XR0 321 
J 0
(-2336 3750);
DISPLAY 0.638298 (-2336 3750);
PAINT MONO (-2336 3750);
FORCEPROP 2 LAST CDS_LIB standard
J 0
(-2525 3750);
DISPLAY INVISIBLE (-2525 3750);
FORCEPROP 1 LAST OFFPAGE TRUE
J 0
(-2200 3625);
DISPLAY 0.872340 (-2200 3625);
PAINT GREEN (-2200 3625);
DISPLAY INVISIBLE (-2200 3625);
FORCEPROP 1 LAST COMMENT_BODY TRUE
J 0
(-2570 3655);
DISPLAY 0.872340 (-2570 3655);
PAINT GREEN (-2570 3655);
DISPLAY INVISIBLE (-2570 3655);
FORCEPROP 2 LAST PATH I71
J 0
(-2325 3800);
DISPLAY 0.680851 (-2325 3800);
DISPLAY INVISIBLE (-2325 3800);
FORCEADD OFFPAGE..2
(-2525 3650);
FORCEPROP 2 LAST $XR0 332 
J 0
(-2336 3650);
DISPLAY 0.638298 (-2336 3650);
PAINT MONO (-2336 3650);
FORCEPROP 2 LAST CDS_LIB standard
J 0
(-2525 3650);
DISPLAY INVISIBLE (-2525 3650);
FORCEPROP 1 LAST OFFPAGE TRUE
J 0
(-2200 3525);
DISPLAY 0.872340 (-2200 3525);
PAINT GREEN (-2200 3525);
DISPLAY INVISIBLE (-2200 3525);
FORCEPROP 1 LAST COMMENT_BODY TRUE
J 0
(-2570 3555);
DISPLAY 0.872340 (-2570 3555);
PAINT GREEN (-2570 3555);
DISPLAY INVISIBLE (-2570 3555);
FORCEPROP 2 LAST PATH I72
J 0
(-2325 3700);
DISPLAY 0.680851 (-2325 3700);
DISPLAY INVISIBLE (-2325 3700);
FORCEADD OFFPAGE..2
(-2525 3700);
FORCEPROP 2 LAST $XR0 321 
J 0
(-2336 3700);
DISPLAY 0.638298 (-2336 3700);
PAINT MONO (-2336 3700);
FORCEPROP 2 LAST CDS_LIB standard
J 0
(-2525 3700);
DISPLAY INVISIBLE (-2525 3700);
FORCEPROP 1 LAST OFFPAGE TRUE
J 0
(-2200 3575);
DISPLAY 0.872340 (-2200 3575);
PAINT GREEN (-2200 3575);
DISPLAY INVISIBLE (-2200 3575);
FORCEPROP 1 LAST COMMENT_BODY TRUE
J 0
(-2570 3605);
DISPLAY 0.872340 (-2570 3605);
PAINT GREEN (-2570 3605);
DISPLAY INVISIBLE (-2570 3605);
FORCEPROP 2 LAST PATH I73
J 0
(-2325 3750);
DISPLAY 0.680851 (-2325 3750);
DISPLAY INVISIBLE (-2325 3750);
FORCEADD Q_RES..2
(-2750 2775);
FORCEPROP 1 LAST LOCATION R6803
J 0
(-2705 2900);
DISPLAY 0.638298 (-2705 2900);
FORCEPROP 0 LAST $SEC 1
J 0
(-2700 2950);
DISPLAY 0.680851 (-2700 2950);
PAINT MONO (-2700 2950);
DISPLAY INVISIBLE (-2700 2950);
FORCEPROP 0 LAST CDS_SEC 1
J 0
(-2700 2950);
DISPLAY 0.680851 (-2700 2950);
DISPLAY INVISIBLE (-2700 2950);
FORCEPROP 1 LASTPIN (-2750 2875) $PN 1
J 0
(-2745 2837);
DISPLAY 0.787234 (-2745 2837);
PAINT MONO (-2745 2837);
FORCEPROP 1 LASTPIN (-2750 2675) $PN 2
J 0
(-2745 2685);
DISPLAY 0.787234 (-2745 2685);
PAINT MONO (-2745 2685);
FORCEPROP 1 LAST WATTAGE 1/16W
J 0
(-2710 2750);
DISPLAY 0.510638 (-2710 2750);
FORCEPROP 1 LAST TOLERANCE 1%
J 0
(-2705 2800);
DISPLAY 0.510638 (-2705 2800);
FORCEPROP 1 LAST VALUE 10K
J 0
(-2705 2850);
DISPLAY 0.510638 (-2705 2850);
FORCEPROP 1 LAST MATERIAL CHIP
J 0
(-2710 2700);
DISPLAY 0.510638 (-2710 2700);
FORCEPROP 1 LAST PACK_TYPE 0402LF
J 0
(-2700 2650);
DISPLAY 0.510638 (-2700 2650);
FORCEPROP 2 LAST CDS_LIB pure_quanta
J 0
(-2750 2775);
DISPLAY INVISIBLE (-2750 2775);
FORCEPROP 1 LAST PATH I76
J 0
(-2700 2950);
DISPLAY 0.978723 (-2700 2950);
PAINT WHITE (-2700 2950);
DISPLAY INVISIBLE (-2700 2950);
FORCEPROP 1 LAST PART_NUMBER CS31002FB08
J 0
(-2710 2650);
DISPLAY 0.510638 (-2710 2650);
DISPLAY INVISIBLE (-2710 2650);
FORCEADD Q_CAP..1
(-7175 5650);
FORCEPROP 1 LAST LOCATION C82
J 0
(-7125 5750);
DISPLAY 0.808511 (-7125 5750);
FORCEPROP 0 LAST $SEC 1
J 0
(-7125 5800);
DISPLAY 0.680851 (-7125 5800);
PAINT MONO (-7125 5800);
DISPLAY INVISIBLE (-7125 5800);
FORCEPROP 0 LAST CDS_SEC 1
J 0
(-7125 5800);
DISPLAY 0.680851 (-7125 5800);
DISPLAY INVISIBLE (-7125 5800);
FORCEPROP 1 LASTPIN (-7175 5750) $PN 1
J 0
(-7165 5730);
DISPLAY 0.787234 (-7165 5730);
PAINT MONO (-7165 5730);
FORCEPROP 1 LASTPIN (-7175 5550) $PN 2
J 0
(-7165 5530);
DISPLAY 0.787234 (-7165 5530);
PAINT MONO (-7165 5530);
FORCEPROP 1 LAST TOLERANCE 20%
J 0
(-7125 5600);
DISPLAY 0.510638 (-7125 5600);
FORCEPROP 1 LAST MATERIAL X6S
J 0
(-7125 5550);
DISPLAY 0.510638 (-7125 5550);
FORCEPROP 1 LAST PACK_TYPE C0402
J 0
(-7125 5500);
DISPLAY 0.510638 (-7125 5500);
FORCEPROP 1 LAST VOLTAGE 6.3V
J 0
(-7125 5650);
DISPLAY 0.510638 (-7125 5650);
FORCEPROP 1 LAST VALUE 10UF
J 0
(-7125 5700);
DISPLAY 0.510638 (-7125 5700);
FORCEPROP 2 LAST CDS_LIB pure_quanta
J 0
(-7175 5650);
DISPLAY INVISIBLE (-7175 5650);
FORCEPROP 1 LAST PATH I77
J 0
(-7125 5800);
DISPLAY 0.978723 (-7125 5800);
PAINT WHITE (-7125 5800);
DISPLAY INVISIBLE (-7125 5800);
FORCEPROP 1 LAST PART_NUMBER CH6101MEB01
J 0
(-7125 5450);
DISPLAY 0.510638 (-7125 5450);
DISPLAY INVISIBLE (-7125 5450);
FORCEADD Q_CAP..1
(-7150 4850);
FORCEPROP 1 LAST LOCATION C83
J 0
(-7100 4950);
DISPLAY 0.808511 (-7100 4950);
FORCEPROP 0 LAST $SEC 1
J 0
(-7100 5000);
DISPLAY 0.680851 (-7100 5000);
PAINT MONO (-7100 5000);
DISPLAY INVISIBLE (-7100 5000);
FORCEPROP 0 LAST CDS_SEC 1
J 0
(-7100 5000);
DISPLAY 0.680851 (-7100 5000);
DISPLAY INVISIBLE (-7100 5000);
FORCEPROP 1 LASTPIN (-7150 4950) $PN 1
J 0
(-7140 4930);
DISPLAY 0.787234 (-7140 4930);
PAINT MONO (-7140 4930);
FORCEPROP 1 LASTPIN (-7150 4750) $PN 2
J 0
(-7140 4730);
DISPLAY 0.787234 (-7140 4730);
PAINT MONO (-7140 4730);
FORCEPROP 1 LAST TOLERANCE 20%
J 0
(-7100 4800);
DISPLAY 0.510638 (-7100 4800);
FORCEPROP 1 LAST MATERIAL X6S
J 0
(-7100 4750);
DISPLAY 0.510638 (-7100 4750);
FORCEPROP 1 LAST PACK_TYPE C0402
J 0
(-7100 4700);
DISPLAY 0.510638 (-7100 4700);
FORCEPROP 1 LAST VOLTAGE 6.3V
J 0
(-7100 4850);
DISPLAY 0.510638 (-7100 4850);
FORCEPROP 1 LAST VALUE 10UF
J 0
(-7100 4900);
DISPLAY 0.510638 (-7100 4900);
FORCEPROP 2 LAST CDS_LIB pure_quanta
J 0
(-7150 4850);
DISPLAY INVISIBLE (-7150 4850);
FORCEPROP 1 LAST PATH I78
J 0
(-7100 5000);
DISPLAY 0.978723 (-7100 5000);
PAINT WHITE (-7100 5000);
DISPLAY INVISIBLE (-7100 5000);
FORCEPROP 1 LAST PART_NUMBER CH6101MEB01
J 0
(-7100 4650);
DISPLAY 0.510638 (-7100 4650);
DISPLAY INVISIBLE (-7100 4650);
FORCEADD Q_CAP..1
(-4600 5300);
FORCEPROP 1 LAST LOCATION C28
J 0
(-4550 5400);
DISPLAY 0.808511 (-4550 5400);
FORCEPROP 0 LAST $SEC 1
J 0
(-4550 5450);
DISPLAY 0.680851 (-4550 5450);
PAINT MONO (-4550 5450);
DISPLAY INVISIBLE (-4550 5450);
FORCEPROP 0 LAST CDS_SEC 1
J 0
(-4550 5450);
DISPLAY 0.680851 (-4550 5450);
DISPLAY INVISIBLE (-4550 5450);
FORCEPROP 1 LASTPIN (-4600 5400) $PN 1
J 0
(-4590 5380);
DISPLAY 0.787234 (-4590 5380);
PAINT MONO (-4590 5380);
FORCEPROP 1 LASTPIN (-4600 5200) $PN 2
J 0
(-4590 5180);
DISPLAY 0.787234 (-4590 5180);
PAINT MONO (-4590 5180);
FORCEPROP 1 LAST MATERIAL X6S
J 0
(-4550 5200);
DISPLAY 0.510638 (-4550 5200);
FORCEPROP 1 LAST VALUE 10UF
J 0
(-4550 5350);
DISPLAY 0.510638 (-4550 5350);
FORCEPROP 1 LAST VOLTAGE 6.3V
J 0
(-4550 5300);
DISPLAY 0.510638 (-4550 5300);
FORCEPROP 1 LAST PACK_TYPE C0402
J 0
(-4550 5150);
DISPLAY 0.510638 (-4550 5150);
FORCEPROP 1 LAST TOLERANCE 20%
J 0
(-4550 5250);
DISPLAY 0.510638 (-4550 5250);
FORCEPROP 2 LAST CDS_LIB pure_quanta
J 0
(-4600 5300);
DISPLAY INVISIBLE (-4600 5300);
FORCEPROP 1 LAST PATH I79
J 0
(-4550 5450);
DISPLAY 0.978723 (-4550 5450);
PAINT WHITE (-4550 5450);
DISPLAY INVISIBLE (-4550 5450);
FORCEPROP 1 LAST PART_NUMBER CH6101MEB01
J 0
(-4550 5100);
DISPLAY 0.510638 (-4550 5100);
DISPLAY INVISIBLE (-4550 5100);
FORCEADD UNIVERSAL_GND..1
(-2125 2350);
FORCEPROP 3 LASTPIN (-2125 2400) SIG_NAME GND\g
J 0
(-2115 2410);
DISPLAY 0.659574 (-2115 2410);
PAINT MONO (-2115 2410);
DISPLAY INVISIBLE (-2115 2410);
FORCEPROP 2 LAST CDS_LIB pure_quanta_power
J 0
(-2125 2350);
DISPLAY INVISIBLE (-2125 2350);
FORCEPROP 1 LAST HDL_POWER GND
J 1
(-2100 2275);
DISPLAY 0.872340 (-2100 2275);
PAINT GREEN (-2100 2275);
DISPLAY INVISIBLE (-2100 2275);
FORCEPROP 1 LAST PATH I80
J 0
(-2050 2350);
DISPLAY 0.872340 (-2050 2350);
PAINT AQUA (-2050 2350);
DISPLAY INVISIBLE (-2050 2350);
FORCEADD Q_RES..2
(-7000 3500);
FORCEPROP 1 LAST LOCATION R560
J 0
(-6955 3625);
DISPLAY 0.638298 (-6955 3625);
FORCEPROP 0 LAST $SEC 1
J 0
(-6950 3675);
DISPLAY 0.680851 (-6950 3675);
PAINT MONO (-6950 3675);
DISPLAY INVISIBLE (-6950 3675);
FORCEPROP 0 LAST CDS_SEC 1
J 0
(-6950 3675);
DISPLAY 0.680851 (-6950 3675);
DISPLAY INVISIBLE (-6950 3675);
FORCEPROP 1 LASTPIN (-7000 3600) $PN 1
J 0
(-6995 3562);
DISPLAY 0.787234 (-6995 3562);
PAINT MONO (-6995 3562);
FORCEPROP 1 LASTPIN (-7000 3400) $PN 2
J 0
(-6995 3410);
DISPLAY 0.787234 (-6995 3410);
PAINT MONO (-6995 3410);
FORCEPROP 1 LAST WATTAGE 1/16W
J 0
(-6960 3475);
DISPLAY 0.510638 (-6960 3475);
FORCEPROP 1 LAST TOLERANCE 1%
J 0
(-6955 3525);
DISPLAY 0.510638 (-6955 3525);
FORCEPROP 1 LAST VALUE 10K
J 0
(-6955 3575);
DISPLAY 0.510638 (-6955 3575);
FORCEPROP 1 LAST MATERIAL CHIP
J 0
(-6960 3425);
DISPLAY 0.510638 (-6960 3425);
FORCEPROP 1 LAST PACK_TYPE 0402LF
J 0
(-6950 3375);
DISPLAY 0.510638 (-6950 3375);
FORCEPROP 2 LAST CDS_LIB pure_quanta
J 0
(-7000 3500);
DISPLAY INVISIBLE (-7000 3500);
FORCEPROP 1 LAST PATH I81
J 0
(-6950 3675);
DISPLAY 0.978723 (-6950 3675);
PAINT WHITE (-6950 3675);
DISPLAY INVISIBLE (-6950 3675);
FORCEPROP 1 LAST PART_NUMBER CS31002FB08
J 0
(-6960 3375);
DISPLAY 0.510638 (-6960 3375);
DISPLAY INVISIBLE (-6960 3375);
FORCEADD UNIVERSAL_POWER..1
(-7000 3800);
FORCEPROP 3 LASTPIN (-7000 3750) SIG_NAME P3V3_AUX\g
J 0
(-6990 3760);
DISPLAY 0.659574 (-6990 3760);
PAINT MONO (-6990 3760);
DISPLAY INVISIBLE (-6990 3760);
FORCEPROP 1 LAST HDL_POWER P3V3_AUX
J 1
(-7000 3850);
DISPLAY 0.872340 (-7000 3850);
PAINT YELLOW (-7000 3850);
FORCEPROP 2 LAST CDS_LIB pure_quanta_power
J 0
(-7000 3800);
DISPLAY INVISIBLE (-7000 3800);
FORCEPROP 1 LAST PATH I82
J 0
(-6950 3825);
DISPLAY 0.872340 (-6950 3825);
PAINT AQUA (-6950 3825);
DISPLAY INVISIBLE (-6950 3825);
FORCEADD OFFPAGE..1
(-6425 3350);
FORCEPROP 2 LAST $XR0 151 
J 0
(-6677 3350);
DISPLAY 0.638298 (-6677 3350);
PAINT MONO (-6677 3350);
FORCEPROP 2 LAST CDS_LIB standard
J 0
(-6425 3350);
DISPLAY INVISIBLE (-6425 3350);
FORCEPROP 1 LAST OFFPAGE TRUE
J 0
(-6100 3225);
DISPLAY 1.170213 (-6100 3225);
PAINT GREEN (-6100 3225);
DISPLAY INVISIBLE (-6100 3225);
FORCEPROP 1 LAST COMMENT_BODY TRUE
J 0
(-6300 3250);
DISPLAY 1.170213 (-6300 3250);
PAINT GREEN (-6300 3250);
DISPLAY INVISIBLE (-6300 3250);
FORCEPROP 2 LAST PATH I9
J 0
(-6675 3400);
DISPLAY 0.680851 (-6675 3400);
DISPLAY INVISIBLE (-6675 3400);
FORCEADD QUANTA_TITLE_BLOCK_C..1
(0 0);
FORCEPROP 0 LAST CDS_CON_LAST_MODIFIED Thu Sep 14 16:12:57 2023
J 0
(-1885 15);
DISPLAY INVISIBLE (-1885 15);
FORCEPROP 1 LAST CUSTOM_TXT_CDS <CON_LAST_MODIFIED>
J 0
(-1885 15);
DISPLAY 0.978723 (-1885 15);
FORCEPROP 2 LAST CUSTOM_TXT_CDS <XR_PAGE_TITLE>
J 0
(-7890 5250);
DISPLAY 0.638298 (-7890 5250);
PAINT PINK (-7890 5250);
DISPLAY INVISIBLE (-7890 5250);
FORCEPROP 1 LAST CUSTOM_TXT_CDS <NAME_2>
J 0
(-3175 50);
FORCEPROP 1 LAST CUSTOM_TXT_CDS <NAME_1>
J 0
(-3175 175);
FORCEPROP 1 LAST CUSTOM_TXT_CDS <Q_NUMBER>
J 0
(-1403 103);
DISPLAY 1.212766 (-1403 103);
FORCEPROP 1 LAST CUSTOM_TXT_CDS <Q_PROJ>
J 0
(-2382 102);
DISPLAY 1.212766 (-2382 102);
FORCEPROP 1 LAST CUSTOM_TXT_CDS <Q_REV>
J 0
(-184 103);
DISPLAY 1.212766 (-184 103);
FORCEPROP 1 LAST CUSTOM_TXT_CDS <CON_PAGE_NUM> OF <CON_TOTAL_PAGES>
J 0
(-446 18);
DISPLAY 0.978723 (-446 18);
FORCEPROP 1 LAST Q_TITLE CLK BUFFER _ 9ZXL045 _ CPU1 RETIMER
J 0
(-9366 26);
DISPLAY 2.446809 (-9366 26);
PAINT GREEN (-9366 26);
FORCEPROP 2 LAST PAGE_BORDER TRUE
J 0
(-7890 5250);
DISPLAY 0.638298 (-7890 5250);
PAINT PINK (-7890 5250);
DISPLAY INVISIBLE (-7890 5250);
FORCEPROP 2 LAST CDS_LIB pure_quanta
J 0
(0 0);
DISPLAY INVISIBLE (0 0);
FORCEPROP 1 LAST CDS_LMAN_SYM_OUTLINE -9475,6775,100,-125
J 0
(0 0);
DISPLAY 0.468085 (0 0);
PAINT GREEN (0 0);
DISPLAY INVISIBLE (0 0);
FORCEPROP 2 LAST CDS_XR_PAGE_TITLE CR-183 : @T6G_MB_LIB.T6G(SCH_1):PAGE183
J 0
(-7890 5250);
DISPLAY 0.638298 (-7890 5250);
PAINT PINK (-7890 5250);
DISPLAY INVISIBLE (-7890 5250);
FORCEPROP 1 LAST Q_DEPT BU9
J 1
(-3763 49);
DISPLAY 1.957447 (-3763 49);
PAINT GREEN (-3763 49);
DISPLAY INVISIBLE (-3763 49);
FORCEPROP 1 LAST COMMENT_BODY TRUE
J 0
(12 -13);
DISPLAY 0.978723 (12 -13);
PAINT GREEN (12 -13);
DISPLAY INVISIBLE (12 -13);
FORCEADD DNS..2
(-5925 1600);
PAINT RED (-5925 1600);
FORCEPROP 2 LAST CDS_LIB mstr_misc
J 0
(-5925 1600);
DISPLAY INVISIBLE (-5925 1600);
FORCEPROP 1 LAST COMMENT_BODY TRUE
R 1
J 0
(-5850 1375);
DISPLAY 0.872340 (-5850 1375);
PAINT GREEN (-5850 1375);
DISPLAY INVISIBLE (-5850 1375);
WIRE 16 -1 (-3925 900)(-3925 1000);
WIRE 16 -1 (-3925 1825)(-3925 1675);
WIRE 16 -1 (-5150 3800)(-5850 3800);
WIRE 16 -1 (-5850 3800)(-5850 4025);
WIRE 16 -1 (-5925 950)(-5925 1050);
WIRE 16 -1 (-3900 4100)(-3575 4100);
WIRE 16 -1 (-3575 4100)(-3575 4325);
WIRE 16 -1 (-5925 1875)(-5925 1675);
WIRE 16 -1 (-7000 3600)(-7000 3750);
WIRE 16 -1 (-2575 3600)(-3900 3600);
FORCEPROP 2 LAST SIG_NAME CLK_100M_RETIMER_CPU1_P1_R_DN
J 0
(-3735 3610);
DISPLAY 0.702128 (-3735 3610);
PAINT SKYBLUE (-3735 3610);
WIRE 16 -1 (-2575 3750)(-3900 3750);
FORCEPROP 2 LAST SIG_NAME CLK_100M_RETIMER_CPU1_P0_R_DP
J 0
(-3735 3760);
DISPLAY 0.702128 (-3735 3760);
PAINT SKYBLUE (-3735 3760);
WIRE 16 -1 (-3075 3950)(-3900 3950);
FORCEPROP 2 LAST SIG_NAME CLK_9ZXL045_P1_HIBW
J 0
(-3735 3960);
DISPLAY 0.553191 (-3735 3960);
PAINT SKYBLUE (-3735 3960);
WIRE 16 -1 (-8350 5825)(-7850 5825);
FORCEPROP 2 LAST SIG_NAME P3V3_9ZXL045_P1
J 0
(-8260 5835);
DISPLAY 0.638298 (-8260 5835);
PAINT SKYBLUE (-8260 5835);
FORCEPROP 2 LASTPROP $XRERR UNIQUE?
J 0
(-8500 5835);
DISPLAY 0.638298 (-8500 5835);
PAINT MONO (-8500 5835);
DISPLAY INVISIBLE (-8500 5835);
WIRE 16 -1 (-7700 5825)(-7850 5825);
WIRE 16 -1 (-7850 5000)(-7850 5825);
WIRE 16 -1 (-7850 5000)(-7650 5000);
WIRE 16 -1 (-2750 2675)(-2750 2500);
WIRE 16 -1 (-2750 2500)(-2550 2500);
WIRE 16 -1 (-2550 2675)(-2550 2500);
WIRE 16 -1 (-2550 2500)(-2350 2500);
WIRE 16 -1 (-2350 2675)(-2350 2500);
WIRE 16 -1 (-2350 2500)(-2125 2500);
WIRE 16 -1 (-2125 2675)(-2125 2500);
WIRE 16 -1 (-2125 2500)(-2125 2400);
WIRE 16 -1 (-5025 5500)(-4600 5500);
WIRE 16 -1 (-4250 5500)(-4600 5500);
WIRE 16 -1 (-4600 5400)(-4600 5500);
WIRE 16 -1 (-4250 5500)(-4000 5500);
WIRE 16 -1 (-4250 5400)(-4250 5500);
WIRE 16 -1 (-4000 5500)(-3750 5500);
WIRE 16 -1 (-4000 5400)(-4000 5500);
WIRE 16 -1 (-3500 5500)(-3750 5500);
WIRE 16 -1 (-3750 5400)(-3750 5500);
WIRE 16 -1 (-3225 5500)(-3500 5500);
WIRE 16 -1 (-3500 5500)(-3500 5400);
WIRE 16 -1 (-3225 5600)(-3225 5500);
WIRE 16 -1 (-3225 5500)(-3225 5400);
WIRE 16 -1 (-4600 5200)(-4600 5075);
WIRE 16 -1 (-4600 5075)(-4250 5075);
WIRE 16 -1 (-4250 5075)(-4000 5075);
WIRE 16 -1 (-4250 5200)(-4250 5075);
WIRE 16 -1 (-4000 5200)(-4000 5075);
WIRE 16 -1 (-3750 5075)(-4000 5075);
WIRE 16 -1 (-3750 5200)(-3750 5075);
WIRE 16 -1 (-3750 5075)(-3500 5075);
WIRE 16 -1 (-3500 5075)(-3500 5200);
WIRE 16 -1 (-3225 5075)(-3500 5075);
WIRE 16 -1 (-3225 5200)(-3225 5075);
WIRE 16 -1 (-3225 5000)(-3225 5075);
WIRE 16 -1 (-3900 2850)(-3700 2850);
WIRE 16 -1 (-3700 2600)(-3700 2850);
WIRE 16 -1 (-5150 3900)(-5450 3900);
WIRE 16 -1 (-5450 3900)(-5450 3950);
WIRE 16 -1 (-5150 3950)(-5450 3950);
WIRE 16 -1 (-5450 3950)(-5450 4000);
WIRE 16 -1 (-5150 4000)(-5450 4000);
WIRE 16 -1 (-5450 4000)(-5450 4050);
WIRE 16 -1 (-5450 4050)(-5450 4100);
WIRE 16 -1 (-5150 4050)(-5450 4050);
WIRE 16 -1 (-5150 4100)(-5450 4100);
WIRE 16 -1 (-5450 4100)(-5450 4325);
WIRE 16 -1 (-6825 5850)(-6825 5825);
WIRE 16 -1 (-6825 5825)(-6825 5750);
WIRE 16 -1 (-7175 5825)(-6825 5825);
WIRE 16 -1 (-7175 5825)(-7175 5750);
WIRE 16 -1 (-7500 5825)(-7175 5825);
WIRE 16 -1 (-6800 5000)(-6800 4950);
WIRE 16 -1 (-6800 5050)(-6800 5000);
WIRE 16 -1 (-7150 5000)(-6800 5000);
WIRE 16 -1 (-7150 4950)(-7150 5000);
WIRE 16 -1 (-7450 5000)(-7150 5000);
WIRE 16 -1 (-6800 4625)(-6800 4750);
WIRE 16 -1 (-7150 4625)(-6800 4625);
WIRE 16 -1 (-6800 4525)(-6800 4625);
WIRE 16 -1 (-7150 4750)(-7150 4625);
WIRE 16 -1 (-8550 5825)(-8875 5825);
WIRE 16 -1 (-8875 5875)(-8875 5825);
WIRE 16 -1 (-6825 5425)(-6825 5550);
WIRE 16 -1 (-6825 5325)(-6825 5425);
WIRE 16 -1 (-7175 5425)(-6825 5425);
WIRE 16 -1 (-7175 5550)(-7175 5425);
WIRE 16 -1 (-5575 5500)(-5225 5500);
WIRE 16 -1 (-5575 5575)(-5575 5500);
WIRE 16 -1 (-7000 3400)(-7000 3250);
WIRE 16 -1 (-5150 3250)(-7000 3250);
FORCEPROP 2 LAST SIG_NAME FM_9ZXL045_P1_DEV_EN
J 0
(-6185 3260);
DISPLAY 0.680851 (-6185 3260);
PAINT SKYBLUE (-6185 3260);
FORCEPROP 2 LASTPROP $XRERR UNIQUE?
J 0
(-6425 3260);
DISPLAY 0.638298 (-6425 3260);
PAINT MONO (-6425 3260);
DISPLAY INVISIBLE (-6425 3260);
WIRE 16 -1 (-2750 3050)(-2750 2875);
WIRE 16 -1 (-3900 3050)(-2750 3050);
FORCEPROP 2 LAST SIG_NAME FM_9ZXL045_P1_3_OE_N
J 0
(-3735 3060);
DISPLAY 0.680851 (-3735 3060);
PAINT SKYBLUE (-3735 3060);
FORCEPROP 2 LASTPROP $XRERR UNIQUE?
J 0
(-3975 3060);
DISPLAY 0.638298 (-3975 3060);
PAINT MONO (-3975 3060);
DISPLAY INVISIBLE (-3975 3060);
WIRE 16 -1 (-2550 3100)(-2550 2875);
WIRE 16 -1 (-3900 3100)(-2550 3100);
FORCEPROP 0 LAST SIG_NAME FM_9ZXL045_P1_2_OE_N
J 0
(-3735 3110);
DISPLAY 0.680851 (-3735 3110);
PAINT SKYBLUE (-3735 3110);
FORCEPROP 2 LASTPROP $XRERR UNIQUE?
J 0
(-3975 3110);
DISPLAY 0.638298 (-3975 3110);
PAINT MONO (-3975 3110);
DISPLAY INVISIBLE (-3975 3110);
WIRE 16 -1 (-2350 3150)(-2350 2875);
WIRE 16 -1 (-3900 3150)(-2350 3150);
FORCEPROP 2 LAST SIG_NAME FM_9ZXL045_P1_1_OE_N
J 0
(-3735 3160);
DISPLAY 0.680851 (-3735 3160);
PAINT SKYBLUE (-3735 3160);
FORCEPROP 2 LASTPROP $XRERR UNIQUE?
J 0
(-3975 3160);
DISPLAY 0.638298 (-3975 3160);
PAINT MONO (-3975 3160);
DISPLAY INVISIBLE (-3975 3160);
WIRE 16 -1 (-5150 3000)(-6575 3000);
FORCEPROP 2 LAST SIG_NAME NC_U10_NC0
J 0
(-6060 3010);
DISPLAY 0.680851 (-6060 3010);
PAINT SKYBLUE (-6060 3010);
FORCEPROP 2 LASTPROP $XRERR UNIQUE?
J 0
(-6815 3000);
DISPLAY 0.638298 (-6815 3000);
PAINT MONO (-6815 3000);
DISPLAY INVISIBLE (-6815 3000);
WIRE 16 -1 (-5150 2850)(-6575 2850);
FORCEPROP 2 LAST SIG_NAME NC_U10_NC3
J 0
(-6060 2860);
DISPLAY 0.680851 (-6060 2860);
PAINT SKYBLUE (-6060 2860);
FORCEPROP 2 LASTPROP $XRERR UNIQUE?
J 0
(-6815 2850);
DISPLAY 0.638298 (-6815 2850);
PAINT MONO (-6815 2850);
DISPLAY INVISIBLE (-6815 2850);
WIRE 16 -1 (-2125 3200)(-2125 2875);
WIRE 16 -1 (-3900 3200)(-2125 3200);
FORCEPROP 2 LAST SIG_NAME FM_9ZXL045_P1_0_OE_N
J 0
(-3735 3210);
DISPLAY 0.680851 (-3735 3210);
PAINT SKYBLUE (-3735 3210);
FORCEPROP 2 LASTPROP $XRERR UNIQUE?
J 0
(-3975 3210);
DISPLAY 0.638298 (-3975 3210);
PAINT MONO (-3975 3210);
DISPLAY INVISIBLE (-3975 3210);
WIRE 16 -1 (-2575 3400)(-3900 3400);
FORCEPROP 2 LAST SIG_NAME CLK_100M_RETIMER_CPU1_P3_R_DN
J 0
(-3735 3410);
DISPLAY 0.702128 (-3735 3410);
PAINT SKYBLUE (-3735 3410);
WIRE 16 -1 (-5150 3150)(-6575 3150);
FORCEPROP 2 LAST SIG_NAME NC_U10_FBOUT_N
J 0
(-6060 3160);
DISPLAY 0.680851 (-6060 3160);
PAINT SKYBLUE (-6060 3160);
FORCEPROP 2 LASTPROP $XRERR UNIQUE?
J 0
(-6815 3150);
DISPLAY 0.638298 (-6815 3150);
PAINT MONO (-6815 3150);
DISPLAY INVISIBLE (-6815 3150);
WIRE 16 -1 (-5150 3200)(-6575 3200);
FORCEPROP 2 LAST SIG_NAME NC_U10_FBOUT
J 0
(-6060 3210);
DISPLAY 0.680851 (-6060 3210);
PAINT SKYBLUE (-6060 3210);
FORCEPROP 2 LASTPROP $XRERR UNIQUE?
J 0
(-6815 3200);
DISPLAY 0.638298 (-6815 3200);
PAINT MONO (-6815 3200);
DISPLAY INVISIBLE (-6815 3200);
WIRE 16 -1 (-5150 3350)(-6375 3350);
FORCEPROP 2 LAST SIG_NAME SMB_9ZXL045_P1_SCL
J 0
(-6310 3360);
DISPLAY 0.702128 (-6310 3360);
PAINT SKYBLUE (-6310 3360);
WIRE 16 -1 (-5150 3400)(-6375 3400);
FORCEPROP 2 LAST SIG_NAME SMB_9ZXL045_P1_SDA
J 0
(-6310 3410);
DISPLAY 0.702128 (-6310 3410);
PAINT SKYBLUE (-6310 3410);
WIRE 16 -1 (-5150 3500)(-6150 3500);
FORCEPROP 2 LAST SIG_NAME CLK_9ZXL045_P1_SADR0
J 0
(-6085 3510);
DISPLAY 0.702128 (-6085 3510);
PAINT SKYBLUE (-6085 3510);
WIRE 16 -1 (-5150 3600)(-6150 3600);
FORCEPROP 2 LAST SIG_NAME CLK_100M_CPU1_CLK13_DN
J 0
(-6085 3610);
DISPLAY 0.680851 (-6085 3610);
PAINT SKYBLUE (-6085 3610);
WIRE 16 -1 (-5150 3650)(-6150 3650);
FORCEPROP 2 LAST SIG_NAME CLK_100M_CPU1_CLK13_DP
J 0
(-6085 3660);
DISPLAY 0.680851 (-6085 3660);
PAINT SKYBLUE (-6085 3660);
WIRE 16 -1 (-2575 3650)(-3900 3650);
FORCEPROP 2 LAST SIG_NAME CLK_100M_RETIMER_CPU1_P1_R_DP
J 0
(-3735 3660);
DISPLAY 0.702128 (-3735 3660);
PAINT SKYBLUE (-3735 3660);
WIRE 16 -1 (-5150 2900)(-6575 2900);
FORCEPROP 2 LAST SIG_NAME NC_U10_NC2
J 0
(-6060 2910);
DISPLAY 0.680851 (-6060 2910);
PAINT SKYBLUE (-6060 2910);
FORCEPROP 2 LASTPROP $XRERR UNIQUE?
J 0
(-6815 2900);
DISPLAY 0.638298 (-6815 2900);
PAINT MONO (-6815 2900);
DISPLAY INVISIBLE (-6815 2900);
WIRE 16 -1 (-5150 2950)(-6575 2950);
FORCEPROP 2 LAST SIG_NAME NC_U10_NC1
J 0
(-6060 2960);
DISPLAY 0.680851 (-6060 2960);
PAINT SKYBLUE (-6060 2960);
FORCEPROP 2 LASTPROP $XRERR UNIQUE?
J 0
(-6815 2950);
DISPLAY 0.638298 (-6815 2950);
PAINT MONO (-6815 2950);
DISPLAY INVISIBLE (-6815 2950);
WIRE 16 -1 (-5925 1250)(-5925 1350);
WIRE 16 -1 (-5250 1350)(-5925 1350);
FORCEPROP 2 LAST SIG_NAME CLK_9ZXL045_P1_SADR0
J 0
(-5860 1360);
DISPLAY 0.553191 (-5860 1360);
PAINT SKYBLUE (-5860 1360);
WIRE 16 -1 (-5925 1475)(-5925 1350);
WIRE 16 -1 (-2575 3700)(-3900 3700);
FORCEPROP 2 LAST SIG_NAME CLK_100M_RETIMER_CPU1_P0_R_DN
J 0
(-3735 3710);
DISPLAY 0.702128 (-3735 3710);
PAINT SKYBLUE (-3735 3710);
WIRE 16 -1 (-2575 3550)(-3900 3550);
FORCEPROP 2 LAST SIG_NAME CLK_100M_RETIMER_CPU1_P2_R_DP
J 0
(-3735 3560);
DISPLAY 0.702128 (-3735 3560);
PAINT SKYBLUE (-3735 3560);
WIRE 16 -1 (-2575 3450)(-3900 3450);
FORCEPROP 0 LAST SIG_NAME CLK_100M_RETIMER_CPU1_P3_R_DP
J 0
(-3735 3460);
DISPLAY 0.702128 (-3735 3460);
PAINT SKYBLUE (-3735 3460);
WIRE 16 -1 (-2575 3500)(-3900 3500);
FORCEPROP 2 LAST SIG_NAME CLK_100M_RETIMER_CPU1_P2_R_DN
J 0
(-3735 3510);
DISPLAY 0.702128 (-3735 3510);
PAINT SKYBLUE (-3735 3510);
WIRE 16 -1 (-3250 1350)(-3925 1350);
FORCEPROP 2 LAST SIG_NAME CLK_9ZXL045_P1_HIBW
J 0
(-3860 1360);
DISPLAY 0.553191 (-3860 1360);
PAINT SKYBLUE (-3860 1360);
WIRE 16 -1 (-3925 1475)(-3925 1350);
WIRE 16 -1 (-3925 1350)(-3925 1200);
DOT 1 (-5450 4100);
DOT 1 (-5450 4050);
DOT 1 (-5450 4000);
DOT 1 (-3225 5500);
DOT 1 (-4000 5500);
DOT 1 (-6800 5000);
DOT 1 (-3225 5075);
DOT 1 (-3500 5500);
DOT 1 (-3750 5500);
DOT 1 (-3500 5075);
DOT 1 (-3750 5075);
DOT 1 (-4250 5500);
DOT 1 (-4000 5075);
DOT 1 (-4250 5075);
DOT 1 (-5450 3950);
DOT 1 (-6825 5825);
DOT 1 (-6800 4625);
DOT 1 (-7850 5825);
DOT 1 (-3925 1350);
DOT 1 (-5925 1350);
DOT 1 (-6825 5425);
DOT 1 (-7175 5825);
DOT 1 (-7150 5000);
DOT 1 (-4600 5500);
DOT 1 (-2125 2500);
DOT 1 (-2550 2500);
DOT 1 (-2350 2500);
FORCENOTE
9ZXL045 ADDRESS: 0XD8(8-BIT)/0X6C(7-BIT)
(-6150 2325) 0;
DISPLAY LEFT (-6150 2325);
DISPLAY 1.595745 (-6150 2325);
PAINT SKYBLUE (-6150 2325);
QUIT
